FILE_TYPE = MACRO_DRAWING;
SET COLOR_WIRE YELLOW;
SET COLOR_PROP ORANGE;
SET COLOR_DOT WHITE;
SET COLOR_ARC YELLOW;
SET COLOR_BODY GREEN;
SET COLOR_NOTE PURPLE;
SET PROP_DISPLAY VALUE;
SET PAGE_NUMBER P181;
FORCEADD UNIVERSAL_GND..1
(-11525 1600);
FORCEPROP 3 LASTPIN (-11525 1650) SIG_NAME GND\g
J 0
(-11515 1660);
DISPLAY 0.659574 (-11515 1660);
PAINT MONO (-11515 1660);
DISPLAY INVISIBLE (-11515 1660);
FORCEPROP 2 LAST CDS_LIB pure_quanta_power
J 0
(-11525 1600);
PAINT MONO (-11525 1600);
DISPLAY INVISIBLE (-11525 1600);
FORCEPROP 1 LAST PATH I1
J 0
(-11450 1600);
DISPLAY 0.872340 (-11450 1600);
PAINT AQUA (-11450 1600);
DISPLAY INVISIBLE (-11450 1600);
FORCEPROP 1 LAST HDL_POWER GND
J 1
(-11500 1525);
DISPLAY 0.872340 (-11500 1525);
PAINT GREEN (-11500 1525);
DISPLAY INVISIBLE (-11500 1525);
FORCEADD Q_CAP..1
(-8650 6075);
FORCEPROP 1 LAST LOCATION PC177_3
J 0
(-8575 6225);
DISPLAY 0.489362 (-8575 6225);
PAINT SKYBLUE (-8575 6225);
FORCEPROP 0 LAST $SEC 1
J 0
(-8600 6225);
DISPLAY 0.680851 (-8600 6225);
PAINT MONO (-8600 6225);
DISPLAY INVISIBLE (-8600 6225);
FORCEPROP 0 LAST CDS_SEC 1
J 0
(-8600 6225);
DISPLAY 1.021277 (-8600 6225);
DISPLAY INVISIBLE (-8600 6225);
FORCEPROP 1 LASTPIN (-8650 6175) $PN 1
J 0
(-8640 6155);
DISPLAY 0.489362 (-8640 6155);
PAINT MONO (-8640 6155);
FORCEPROP 1 LASTPIN (-8650 5975) $PN 2
J 0
(-8640 5955);
DISPLAY 0.489362 (-8640 5955);
PAINT MONO (-8640 5955);
FORCEPROP 1 LAST MATERIAL X7R
J 0
(-8575 6025);
DISPLAY 0.489362 (-8575 6025);
PAINT SKYBLUE (-8575 6025);
FORCEPROP 1 LAST TOLERANCE 10%
J 0
(-8575 6075);
DISPLAY 0.489362 (-8575 6075);
PAINT SKYBLUE (-8575 6075);
FORCEPROP 1 LAST VALUE 0.1UF
J 0
(-8575 6175);
DISPLAY 0.489362 (-8575 6175);
PAINT SKYBLUE (-8575 6175);
FORCEPROP 1 LAST VOLTAGE 25V
J 0
(-8575 6125);
DISPLAY 0.489362 (-8575 6125);
PAINT SKYBLUE (-8575 6125);
FORCEPROP 1 LAST PACK_TYPE 0402
J 0
(-8575 5925);
DISPLAY 0.489362 (-8575 5925);
PAINT SKYBLUE (-8575 5925);
FORCEPROP 1 LAST PART_NUMBER CH4104K1B00
J 0
(-8575 5975);
DISPLAY 0.489362 (-8575 5975);
PAINT SKYBLUE (-8575 5975);
FORCEPROP 2 LAST CDS_LIB pure_quanta
J 0
(-8650 6075);
DISPLAY INVISIBLE (-8650 6075);
FORCEPROP 1 LAST PATH I100
J 0
(-8600 6225);
DISPLAY 0.978723 (-8600 6225);
PAINT WHITE (-8600 6225);
DISPLAY INVISIBLE (-8600 6225);
FORCEADD Q_CAP..1
(-8625 3300);
FORCEPROP 1 LAST LOCATION PC178_4
J 0
(-8550 3425);
DISPLAY 0.489362 (-8550 3425);
PAINT SKYBLUE (-8550 3425);
FORCEPROP 0 LAST $SEC 1
J 0
(-8575 3450);
DISPLAY 0.680851 (-8575 3450);
PAINT MONO (-8575 3450);
DISPLAY INVISIBLE (-8575 3450);
FORCEPROP 0 LAST CDS_SEC 1
J 0
(-8575 3450);
DISPLAY 1.021277 (-8575 3450);
DISPLAY INVISIBLE (-8575 3450);
FORCEPROP 1 LASTPIN (-8625 3400) $PN 1
J 0
(-8615 3380);
DISPLAY 0.489362 (-8615 3380);
PAINT MONO (-8615 3380);
FORCEPROP 1 LASTPIN (-8625 3200) $PN 2
J 0
(-8615 3180);
DISPLAY 0.489362 (-8615 3180);
PAINT MONO (-8615 3180);
FORCEPROP 1 LAST MATERIAL X7R
J 0
(-8550 3225);
DISPLAY 0.489362 (-8550 3225);
PAINT SKYBLUE (-8550 3225);
FORCEPROP 1 LAST TOLERANCE 10%
J 0
(-8550 3275);
DISPLAY 0.489362 (-8550 3275);
PAINT SKYBLUE (-8550 3275);
FORCEPROP 1 LAST VALUE 0.1UF
J 0
(-8550 3375);
DISPLAY 0.489362 (-8550 3375);
PAINT SKYBLUE (-8550 3375);
FORCEPROP 1 LAST PART_NUMBER CH4104K1B00
J 0
(-8550 3175);
DISPLAY 0.489362 (-8550 3175);
PAINT SKYBLUE (-8550 3175);
FORCEPROP 1 LAST VOLTAGE 25V
J 0
(-8550 3325);
DISPLAY 0.489362 (-8550 3325);
PAINT SKYBLUE (-8550 3325);
FORCEPROP 1 LAST PACK_TYPE 0402
J 0
(-8550 3125);
DISPLAY 0.489362 (-8550 3125);
PAINT SKYBLUE (-8550 3125);
FORCEPROP 2 LAST CDS_LIB pure_quanta
J 0
(-8625 3300);
DISPLAY INVISIBLE (-8625 3300);
FORCEPROP 1 LAST PATH I101
J 0
(-8575 3450);
DISPLAY 0.978723 (-8575 3450);
PAINT WHITE (-8575 3450);
DISPLAY INVISIBLE (-8575 3450);
FORCEADD Q_CAP..1
(-11175 5425);
FORCEPROP 1 LAST LOCATION PC172
J 0
(-11125 5525);
DISPLAY 0.489362 (-11125 5525);
PAINT SKYBLUE (-11125 5525);
FORCEPROP 0 LAST $SEC 1
J 0
(-11125 5575);
DISPLAY 0.680851 (-11125 5575);
PAINT MONO (-11125 5575);
DISPLAY INVISIBLE (-11125 5575);
FORCEPROP 0 LAST CDS_SEC 1
J 0
(-11125 5575);
DISPLAY 1.021277 (-11125 5575);
DISPLAY INVISIBLE (-11125 5575);
FORCEPROP 1 LASTPIN (-11175 5525) $PN 1
J 0
(-11165 5505);
DISPLAY 0.489362 (-11165 5505);
PAINT MONO (-11165 5505);
FORCEPROP 1 LASTPIN (-11175 5325) $PN 2
J 0
(-11165 5305);
DISPLAY 0.489362 (-11165 5305);
PAINT MONO (-11165 5305);
FORCEPROP 1 LAST MATERIAL X6S
J 0
(-11125 5325);
DISPLAY 0.489362 (-11125 5325);
PAINT SKYBLUE (-11125 5325);
FORCEPROP 1 LAST TOLERANCE 10%
J 0
(-11125 5375);
DISPLAY 0.489362 (-11125 5375);
PAINT SKYBLUE (-11125 5375);
FORCEPROP 1 LAST VALUE 2.2UF
J 0
(-11125 5475);
DISPLAY 0.489362 (-11125 5475);
PAINT SKYBLUE (-11125 5475);
FORCEPROP 1 LAST PART_NUMBER CH5222KEB01
J 0
(-11125 5275);
DISPLAY 0.489362 (-11125 5275);
PAINT SKYBLUE (-11125 5275);
FORCEPROP 1 LAST VOLTAGE 10V
J 0
(-11125 5425);
DISPLAY 0.489362 (-11125 5425);
PAINT SKYBLUE (-11125 5425);
FORCEPROP 1 LAST PACK_TYPE C0402
J 0
(-11125 5225);
DISPLAY 0.489362 (-11125 5225);
PAINT SKYBLUE (-11125 5225);
FORCEPROP 2 LAST CDS_LIB pure_quanta
J 0
(-11175 5425);
DISPLAY INVISIBLE (-11175 5425);
FORCEPROP 1 LAST PATH I102
J 0
(-11125 5575);
DISPLAY 0.978723 (-11125 5575);
PAINT WHITE (-11125 5575);
DISPLAY INVISIBLE (-11125 5575);
FORCEADD UNIVERSAL_GND..1
(-11175 5225);
FORCEPROP 3 LASTPIN (-11175 5275) SIG_NAME GND\g
J 0
(-11165 5285);
DISPLAY 0.659574 (-11165 5285);
PAINT MONO (-11165 5285);
DISPLAY INVISIBLE (-11165 5285);
FORCEPROP 2 LAST CDS_LIB pure_quanta_power
J 0
(-11175 5225);
DISPLAY INVISIBLE (-11175 5225);
FORCEPROP 1 LAST PATH I103
J 0
(-11100 5225);
DISPLAY 0.872340 (-11100 5225);
PAINT AQUA (-11100 5225);
DISPLAY INVISIBLE (-11100 5225);
FORCEPROP 1 LAST HDL_POWER GND
J 1
(-11150 5150);
DISPLAY 0.872340 (-11150 5150);
PAINT GREEN (-11150 5150);
DISPLAY INVISIBLE (-11150 5150);
FORCEADD UNIVERSAL_GND..1
(-10825 5725);
FORCEPROP 3 LASTPIN (-10825 5775) SIG_NAME GND\g
J 0
(-10815 5785);
DISPLAY 0.659574 (-10815 5785);
PAINT MONO (-10815 5785);
DISPLAY INVISIBLE (-10815 5785);
FORCEPROP 2 LAST CDS_LIB pure_quanta_power
J 0
(-10825 5725);
DISPLAY INVISIBLE (-10825 5725);
FORCEPROP 1 LAST PATH I104
J 0
(-10750 5725);
DISPLAY 0.872340 (-10750 5725);
PAINT AQUA (-10750 5725);
DISPLAY INVISIBLE (-10750 5725);
FORCEPROP 1 LAST HDL_POWER GND
J 1
(-10800 5650);
DISPLAY 0.872340 (-10800 5650);
PAINT GREEN (-10800 5650);
DISPLAY INVISIBLE (-10800 5650);
FORCEADD Q_RES..2
(-11175 5975);
FORCEPROP 1 LAST LOCATION PR108
J 0
(-11130 6100);
DISPLAY 0.489362 (-11130 6100);
PAINT SKYBLUE (-11130 6100);
FORCEPROP 0 LAST $SEC 1
J 0
(-11125 6150);
DISPLAY 0.680851 (-11125 6150);
PAINT MONO (-11125 6150);
DISPLAY INVISIBLE (-11125 6150);
FORCEPROP 0 LAST CDS_SEC 1
J 0
(-11125 6150);
DISPLAY 1.021277 (-11125 6150);
DISPLAY INVISIBLE (-11125 6150);
FORCEPROP 1 LASTPIN (-11175 6075) $PN 1
J 0
(-11170 6037);
DISPLAY 0.489362 (-11170 6037);
PAINT MONO (-11170 6037);
FORCEPROP 1 LASTPIN (-11175 5875) $PN 2
J 0
(-11170 5885);
DISPLAY 0.489362 (-11170 5885);
PAINT MONO (-11170 5885);
FORCEPROP 1 LAST WATTAGE 1/16W
J 0
(-11125 5950);
DISPLAY 0.489362 (-11125 5950);
PAINT SKYBLUE (-11125 5950);
FORCEPROP 1 LAST MATERIAL CHIP
J 0
(-11125 5900);
DISPLAY 0.489362 (-11125 5900);
PAINT SKYBLUE (-11125 5900);
FORCEPROP 1 LAST TOLERANCE 1%
J 0
(-11125 6000);
DISPLAY 0.489362 (-11125 6000);
PAINT SKYBLUE (-11125 6000);
FORCEPROP 1 LAST VALUE 2.2
J 0
(-11125 6050);
DISPLAY 0.489362 (-11125 6050);
PAINT SKYBLUE (-11125 6050);
FORCEPROP 1 LAST PART_NUMBER CS-2202FB00
J 0
(-11125 5850);
DISPLAY 0.489362 (-11125 5850);
PAINT SKYBLUE (-11125 5850);
FORCEPROP 1 LAST PACK_TYPE 0402LF
J 0
(-11125 5800);
DISPLAY 0.489362 (-11125 5800);
PAINT SKYBLUE (-11125 5800);
FORCEPROP 2 LAST CDS_LIB pure_quanta
J 0
(-11175 5975);
DISPLAY INVISIBLE (-11175 5975);
FORCEPROP 1 LAST PATH I105
J 0
(-11125 6150);
DISPLAY 0.978723 (-11125 6150);
PAINT WHITE (-11125 6150);
DISPLAY INVISIBLE (-11125 6150);
FORCEADD Q_CAP..1
(-10825 6000);
FORCEPROP 1 LAST LOCATION PC174_IOP0_3
J 0
(-10775 6100);
DISPLAY 0.489362 (-10775 6100);
PAINT SKYBLUE (-10775 6100);
FORCEPROP 0 LAST $SEC 1
J 0
(-10775 6150);
DISPLAY 0.680851 (-10775 6150);
PAINT MONO (-10775 6150);
DISPLAY INVISIBLE (-10775 6150);
FORCEPROP 0 LAST CDS_SEC 1
J 0
(-10775 6150);
DISPLAY 1.021277 (-10775 6150);
DISPLAY INVISIBLE (-10775 6150);
FORCEPROP 1 LASTPIN (-10825 6100) $PN 1
J 0
(-10815 6080);
DISPLAY 0.489362 (-10815 6080);
PAINT MONO (-10815 6080);
FORCEPROP 1 LASTPIN (-10825 5900) $PN 2
J 0
(-10815 5880);
DISPLAY 0.489362 (-10815 5880);
PAINT MONO (-10815 5880);
FORCEPROP 1 LAST MATERIAL X6S
J 0
(-10775 5900);
DISPLAY 0.489362 (-10775 5900);
PAINT SKYBLUE (-10775 5900);
FORCEPROP 1 LAST TOLERANCE 10%
J 0
(-10775 5950);
DISPLAY 0.489362 (-10775 5950);
PAINT SKYBLUE (-10775 5950);
FORCEPROP 1 LAST VALUE 2.2UF
J 0
(-10775 6050);
DISPLAY 0.489362 (-10775 6050);
PAINT SKYBLUE (-10775 6050);
FORCEPROP 1 LAST PART_NUMBER CH5222KEB01
J 0
(-10775 5850);
DISPLAY 0.489362 (-10775 5850);
PAINT SKYBLUE (-10775 5850);
FORCEPROP 1 LAST VOLTAGE 10V
J 0
(-10775 6000);
DISPLAY 0.489362 (-10775 6000);
PAINT SKYBLUE (-10775 6000);
FORCEPROP 1 LAST PACK_TYPE C0402
J 0
(-10775 5800);
DISPLAY 0.489362 (-10775 5800);
PAINT SKYBLUE (-10775 5800);
FORCEPROP 2 LAST CDS_LIB pure_quanta
J 0
(-10825 6000);
DISPLAY INVISIBLE (-10825 6000);
FORCEPROP 1 LAST PATH I106
J 0
(-10775 6150);
DISPLAY 0.978723 (-10775 6150);
PAINT WHITE (-10775 6150);
DISPLAY INVISIBLE (-10775 6150);
FORCEADD Q_CAP..1
(-11200 2725);
FORCEPROP 1 LAST LOCATION PC171
J 0
(-11150 2825);
DISPLAY 0.489362 (-11150 2825);
PAINT SKYBLUE (-11150 2825);
FORCEPROP 0 LAST $SEC 1
J 0
(-11150 2875);
DISPLAY 0.680851 (-11150 2875);
PAINT MONO (-11150 2875);
DISPLAY INVISIBLE (-11150 2875);
FORCEPROP 0 LAST CDS_SEC 1
J 0
(-11150 2875);
DISPLAY 1.021277 (-11150 2875);
DISPLAY INVISIBLE (-11150 2875);
FORCEPROP 1 LASTPIN (-11200 2825) $PN 1
J 0
(-11190 2805);
DISPLAY 0.489362 (-11190 2805);
PAINT MONO (-11190 2805);
FORCEPROP 1 LASTPIN (-11200 2625) $PN 2
J 0
(-11190 2605);
DISPLAY 0.489362 (-11190 2605);
PAINT MONO (-11190 2605);
FORCEPROP 1 LAST MATERIAL X6S
J 0
(-11150 2625);
DISPLAY 0.489362 (-11150 2625);
PAINT SKYBLUE (-11150 2625);
FORCEPROP 1 LAST TOLERANCE 10%
J 0
(-11150 2675);
DISPLAY 0.489362 (-11150 2675);
PAINT SKYBLUE (-11150 2675);
FORCEPROP 1 LAST VALUE 2.2UF
J 0
(-11150 2775);
DISPLAY 0.489362 (-11150 2775);
PAINT SKYBLUE (-11150 2775);
FORCEPROP 1 LAST PART_NUMBER CH5222KEB01
J 0
(-11150 2575);
DISPLAY 0.489362 (-11150 2575);
PAINT SKYBLUE (-11150 2575);
FORCEPROP 1 LAST VOLTAGE 10V
J 0
(-11150 2725);
DISPLAY 0.489362 (-11150 2725);
PAINT SKYBLUE (-11150 2725);
FORCEPROP 1 LAST PACK_TYPE C0402
J 0
(-11150 2525);
DISPLAY 0.489362 (-11150 2525);
PAINT SKYBLUE (-11150 2525);
FORCEPROP 2 LAST CDS_LIB pure_quanta
J 0
(-11200 2725);
DISPLAY INVISIBLE (-11200 2725);
FORCEPROP 1 LAST PATH I108
J 0
(-11150 2875);
DISPLAY 0.978723 (-11150 2875);
PAINT WHITE (-11150 2875);
DISPLAY INVISIBLE (-11150 2875);
FORCEADD UNIVERSAL_GND..1
(-11200 2525);
FORCEPROP 3 LASTPIN (-11200 2575) SIG_NAME GND\g
J 0
(-11190 2585);
DISPLAY 0.659574 (-11190 2585);
PAINT MONO (-11190 2585);
DISPLAY INVISIBLE (-11190 2585);
FORCEPROP 2 LAST CDS_LIB pure_quanta_power
J 0
(-11200 2525);
DISPLAY INVISIBLE (-11200 2525);
FORCEPROP 1 LAST PATH I109
J 0
(-11125 2525);
DISPLAY 0.872340 (-11125 2525);
PAINT AQUA (-11125 2525);
DISPLAY INVISIBLE (-11125 2525);
FORCEPROP 1 LAST HDL_POWER GND
J 1
(-11175 2450);
DISPLAY 0.872340 (-11175 2450);
PAINT GREEN (-11175 2450);
DISPLAY INVISIBLE (-11175 2450);
FORCEADD UNIVERSAL_GND..1
(-10850 3025);
FORCEPROP 3 LASTPIN (-10850 3075) SIG_NAME GND\g
J 0
(-10840 3085);
DISPLAY 0.659574 (-10840 3085);
PAINT MONO (-10840 3085);
DISPLAY INVISIBLE (-10840 3085);
FORCEPROP 2 LAST CDS_LIB pure_quanta_power
J 0
(-10850 3025);
DISPLAY INVISIBLE (-10850 3025);
FORCEPROP 1 LAST PATH I110
J 0
(-10775 3025);
DISPLAY 0.872340 (-10775 3025);
PAINT AQUA (-10775 3025);
DISPLAY INVISIBLE (-10775 3025);
FORCEPROP 1 LAST HDL_POWER GND
J 1
(-10825 2950);
DISPLAY 0.872340 (-10825 2950);
PAINT GREEN (-10825 2950);
DISPLAY INVISIBLE (-10825 2950);
FORCEADD Q_RES..2
(-11200 3275);
FORCEPROP 1 LAST LOCATION PR107
J 0
(-11155 3400);
DISPLAY 0.489362 (-11155 3400);
PAINT SKYBLUE (-11155 3400);
FORCEPROP 0 LAST $SEC 1
J 0
(-11150 3450);
DISPLAY 0.680851 (-11150 3450);
PAINT MONO (-11150 3450);
DISPLAY INVISIBLE (-11150 3450);
FORCEPROP 0 LAST CDS_SEC 1
J 0
(-11150 3450);
DISPLAY 1.021277 (-11150 3450);
DISPLAY INVISIBLE (-11150 3450);
FORCEPROP 1 LASTPIN (-11200 3375) $PN 1
J 0
(-11195 3337);
DISPLAY 0.489362 (-11195 3337);
PAINT MONO (-11195 3337);
FORCEPROP 1 LASTPIN (-11200 3175) $PN 2
J 0
(-11195 3185);
DISPLAY 0.489362 (-11195 3185);
PAINT MONO (-11195 3185);
FORCEPROP 1 LAST WATTAGE 1/16W
J 0
(-11150 3250);
DISPLAY 0.489362 (-11150 3250);
PAINT SKYBLUE (-11150 3250);
FORCEPROP 1 LAST MATERIAL CHIP
J 0
(-11150 3200);
DISPLAY 0.489362 (-11150 3200);
PAINT SKYBLUE (-11150 3200);
FORCEPROP 1 LAST TOLERANCE 1%
J 0
(-11150 3300);
DISPLAY 0.489362 (-11150 3300);
PAINT SKYBLUE (-11150 3300);
FORCEPROP 1 LAST VALUE 2.2
J 0
(-11150 3350);
DISPLAY 0.489362 (-11150 3350);
PAINT SKYBLUE (-11150 3350);
FORCEPROP 1 LAST PART_NUMBER CS-2202FB00
J 0
(-11150 3150);
DISPLAY 0.489362 (-11150 3150);
PAINT SKYBLUE (-11150 3150);
FORCEPROP 1 LAST PACK_TYPE 0402LF
J 0
(-11150 3100);
DISPLAY 0.489362 (-11150 3100);
PAINT SKYBLUE (-11150 3100);
FORCEPROP 2 LAST CDS_LIB pure_quanta
J 0
(-11200 3275);
DISPLAY INVISIBLE (-11200 3275);
FORCEPROP 1 LAST PATH I111
J 0
(-11150 3450);
DISPLAY 0.978723 (-11150 3450);
PAINT WHITE (-11150 3450);
DISPLAY INVISIBLE (-11150 3450);
FORCEADD Q_CAP..1
(-10850 3300);
FORCEPROP 1 LAST LOCATION PC173_IOP0_4
J 0
(-10800 3400);
DISPLAY 0.489362 (-10800 3400);
PAINT SKYBLUE (-10800 3400);
FORCEPROP 0 LAST $SEC 1
J 0
(-10800 3450);
DISPLAY 0.680851 (-10800 3450);
PAINT MONO (-10800 3450);
DISPLAY INVISIBLE (-10800 3450);
FORCEPROP 0 LAST CDS_SEC 1
J 0
(-10800 3450);
DISPLAY 1.021277 (-10800 3450);
DISPLAY INVISIBLE (-10800 3450);
FORCEPROP 1 LASTPIN (-10850 3400) $PN 1
J 0
(-10840 3380);
DISPLAY 0.489362 (-10840 3380);
PAINT MONO (-10840 3380);
FORCEPROP 1 LASTPIN (-10850 3200) $PN 2
J 0
(-10840 3180);
DISPLAY 0.489362 (-10840 3180);
PAINT MONO (-10840 3180);
FORCEPROP 1 LAST MATERIAL X6S
J 0
(-10800 3200);
DISPLAY 0.489362 (-10800 3200);
PAINT SKYBLUE (-10800 3200);
FORCEPROP 1 LAST TOLERANCE 10%
J 0
(-10800 3250);
DISPLAY 0.489362 (-10800 3250);
PAINT SKYBLUE (-10800 3250);
FORCEPROP 1 LAST VALUE 2.2UF
J 0
(-10800 3350);
DISPLAY 0.489362 (-10800 3350);
PAINT SKYBLUE (-10800 3350);
FORCEPROP 1 LAST PART_NUMBER CH5222KEB01
J 0
(-10800 3150);
DISPLAY 0.489362 (-10800 3150);
PAINT SKYBLUE (-10800 3150);
FORCEPROP 1 LAST VOLTAGE 10V
J 0
(-10800 3300);
DISPLAY 0.489362 (-10800 3300);
PAINT SKYBLUE (-10800 3300);
FORCEPROP 1 LAST PACK_TYPE C0402
J 0
(-10800 3100);
DISPLAY 0.489362 (-10800 3100);
PAINT SKYBLUE (-10800 3100);
FORCEPROP 2 LAST CDS_LIB pure_quanta
J 0
(-10850 3300);
DISPLAY INVISIBLE (-10850 3300);
FORCEPROP 1 LAST PATH I112
J 0
(-10800 3450);
DISPLAY 0.978723 (-10800 3450);
PAINT WHITE (-10800 3450);
DISPLAY INVISIBLE (-10800 3450);
FORCEADD UNIVERSAL_GND..1
(-12075 4550);
FORCEPROP 3 LASTPIN (-12075 4600) SIG_NAME GND\g
J 0
(-12065 4610);
DISPLAY 0.659574 (-12065 4610);
PAINT MONO (-12065 4610);
DISPLAY INVISIBLE (-12065 4610);
FORCEPROP 2 LAST CDS_LIB pure_quanta_power
J 0
(-12075 4550);
DISPLAY INVISIBLE (-12075 4550);
FORCEPROP 1 LAST PATH I114
J 0
(-12000 4550);
DISPLAY 0.872340 (-12000 4550);
PAINT AQUA (-12000 4550);
DISPLAY INVISIBLE (-12000 4550);
FORCEPROP 1 LAST HDL_POWER GND
J 1
(-12050 4475);
DISPLAY 0.872340 (-12050 4475);
PAINT GREEN (-12050 4475);
DISPLAY INVISIBLE (-12050 4475);
FORCEADD UNIVERSAL_GND..1
(-12050 1750);
FORCEPROP 3 LASTPIN (-12050 1800) SIG_NAME GND\g
J 0
(-12040 1810);
DISPLAY 0.659574 (-12040 1810);
PAINT MONO (-12040 1810);
DISPLAY INVISIBLE (-12040 1810);
FORCEPROP 2 LAST CDS_LIB pure_quanta_power
J 0
(-12050 1750);
DISPLAY INVISIBLE (-12050 1750);
FORCEPROP 1 LAST PATH I115
J 0
(-11975 1750);
DISPLAY 0.872340 (-11975 1750);
PAINT AQUA (-11975 1750);
DISPLAY INVISIBLE (-11975 1750);
FORCEPROP 1 LAST HDL_POWER GND
J 1
(-12025 1675);
DISPLAY 0.872340 (-12025 1675);
PAINT GREEN (-12025 1675);
DISPLAY INVISIBLE (-12025 1675);
FORCEADD UNIVERSAL_GND..1
(-8100 4175);
FORCEPROP 3 LASTPIN (-8100 4225) SIG_NAME GND\g
J 0
(-8090 4235);
DISPLAY 0.659574 (-8090 4235);
PAINT MONO (-8090 4235);
DISPLAY INVISIBLE (-8090 4235);
FORCEPROP 2 LAST CDS_LIB pure_quanta_power
J 0
(-8100 4175);
DISPLAY INVISIBLE (-8100 4175);
FORCEPROP 1 LAST PATH I117
J 0
(-8025 4175);
DISPLAY 0.872340 (-8025 4175);
PAINT AQUA (-8025 4175);
DISPLAY INVISIBLE (-8025 4175);
FORCEPROP 1 LAST HDL_POWER GND
J 1
(-8075 4100);
DISPLAY 0.872340 (-8075 4100);
PAINT GREEN (-8075 4100);
DISPLAY INVISIBLE (-8075 4100);
FORCEADD Q_RES..2
(-8100 4400);
FORCEPROP 1 LAST LOCATION PR379
J 0
(-8055 4525);
DISPLAY 0.489362 (-8055 4525);
PAINT SKYBLUE (-8055 4525);
FORCEPROP 0 LAST $SEC 1
J 0
(-8050 4575);
DISPLAY 0.680851 (-8050 4575);
PAINT MONO (-8050 4575);
DISPLAY INVISIBLE (-8050 4575);
FORCEPROP 0 LAST CDS_SEC 1
J 0
(-8050 4575);
DISPLAY 1.021277 (-8050 4575);
DISPLAY INVISIBLE (-8050 4575);
FORCEPROP 1 LASTPIN (-8100 4500) $PN 1
J 0
(-8095 4462);
DISPLAY 0.489362 (-8095 4462);
PAINT MONO (-8095 4462);
FORCEPROP 1 LASTPIN (-8100 4300) $PN 2
J 0
(-8095 4310);
DISPLAY 0.489362 (-8095 4310);
PAINT MONO (-8095 4310);
FORCEPROP 1 LAST MATERIAL EMPTY
J 0
(-8060 4325);
DISPLAY 0.489362 (-8060 4325);
PAINT RED (-8060 4325);
FORCEPROP 1 LAST PART_NUMBER CS-1504FB00
J 0
(-8060 4275);
DISPLAY 0.489362 (-8060 4275);
PAINT SKYBLUE (-8060 4275);
FORCEPROP 1 LAST PACK_TYPE 0402LF
J 0
(-8060 4225);
DISPLAY 0.489362 (-8060 4225);
PAINT SKYBLUE (-8060 4225);
FORCEPROP 1 LAST VALUE 1.5
J 0
(-8055 4475);
DISPLAY 0.489362 (-8055 4475);
PAINT SKYBLUE (-8055 4475);
FORCEPROP 1 LAST WATTAGE 1/8W
J 0
(-8060 4375);
DISPLAY 0.489362 (-8060 4375);
PAINT SKYBLUE (-8060 4375);
FORCEPROP 1 LAST TOLERANCE 1%
J 0
(-8055 4425);
DISPLAY 0.489362 (-8055 4425);
PAINT SKYBLUE (-8055 4425);
FORCEPROP 2 LAST CDS_LIB pure_quanta
J 0
(-8100 4400);
DISPLAY INVISIBLE (-8100 4400);
FORCEPROP 1 LAST PATH I118
J 0
(-8050 4575);
DISPLAY 0.978723 (-8050 4575);
PAINT WHITE (-8050 4575);
DISPLAY INVISIBLE (-8050 4575);
FORCEADD Q_CAP..1
(-8100 4925);
FORCEPROP 1 LAST LOCATION PC166
J 0
(-8050 5025);
DISPLAY 0.489362 (-8050 5025);
PAINT SKYBLUE (-8050 5025);
FORCEPROP 0 LAST $SEC 1
J 0
(-8050 5075);
DISPLAY 0.680851 (-8050 5075);
PAINT MONO (-8050 5075);
DISPLAY INVISIBLE (-8050 5075);
FORCEPROP 0 LAST CDS_SEC 1
J 0
(-8050 5075);
DISPLAY 1.021277 (-8050 5075);
DISPLAY INVISIBLE (-8050 5075);
FORCEPROP 1 LASTPIN (-8100 5025) $PN 1
J 0
(-8090 5005);
DISPLAY 0.489362 (-8090 5005);
PAINT MONO (-8090 5005);
FORCEPROP 1 LASTPIN (-8100 4825) $PN 2
J 0
(-8090 4805);
DISPLAY 0.489362 (-8090 4805);
PAINT MONO (-8090 4805);
FORCEPROP 1 LAST MATERIAL EMPTY
J 0
(-8050 4825);
DISPLAY 0.489362 (-8050 4825);
PAINT RED (-8050 4825);
FORCEPROP 1 LAST TOLERANCE 10%
J 0
(-8050 4875);
DISPLAY 0.489362 (-8050 4875);
PAINT SKYBLUE (-8050 4875);
FORCEPROP 1 LAST VALUE 560PF
J 0
(-8050 4975);
DISPLAY 0.489362 (-8050 4975);
PAINT SKYBLUE (-8050 4975);
FORCEPROP 1 LAST PART_NUMBER CH1566K1B09
J 0
(-8050 4775);
DISPLAY 0.489362 (-8050 4775);
PAINT SKYBLUE (-8050 4775);
FORCEPROP 1 LAST VOLTAGE 50V
J 0
(-8050 4925);
DISPLAY 0.489362 (-8050 4925);
PAINT SKYBLUE (-8050 4925);
FORCEPROP 1 LAST PACK_TYPE C0402
J 0
(-8050 4725);
DISPLAY 0.489362 (-8050 4725);
PAINT SKYBLUE (-8050 4725);
FORCEPROP 2 LAST CDS_LIB pure_quanta
J 0
(-8100 4925);
DISPLAY INVISIBLE (-8100 4925);
FORCEPROP 1 LAST PATH I119
J 0
(-8050 5075);
DISPLAY 0.978723 (-8050 5075);
PAINT WHITE (-8050 5075);
DISPLAY INVISIBLE (-8050 5075);
FORCEADD UNIVERSAL_GND..1
(-8100 1375);
FORCEPROP 3 LASTPIN (-8100 1425) SIG_NAME GND\g
J 0
(-8090 1435);
DISPLAY 0.659574 (-8090 1435);
PAINT MONO (-8090 1435);
DISPLAY INVISIBLE (-8090 1435);
FORCEPROP 2 LAST CDS_LIB pure_quanta_power
J 0
(-8100 1375);
DISPLAY INVISIBLE (-8100 1375);
FORCEPROP 1 LAST PATH I120
J 0
(-8025 1375);
DISPLAY 0.872340 (-8025 1375);
PAINT AQUA (-8025 1375);
DISPLAY INVISIBLE (-8025 1375);
FORCEPROP 1 LAST HDL_POWER GND
J 1
(-8075 1300);
DISPLAY 0.872340 (-8075 1300);
PAINT GREEN (-8075 1300);
DISPLAY INVISIBLE (-8075 1300);
FORCEADD Q_RES..2
(-8100 1600);
FORCEPROP 1 LAST LOCATION PR291
J 0
(-8055 1725);
DISPLAY 0.489362 (-8055 1725);
PAINT SKYBLUE (-8055 1725);
FORCEPROP 0 LAST $SEC 1
J 0
(-8050 1775);
DISPLAY 0.680851 (-8050 1775);
PAINT MONO (-8050 1775);
DISPLAY INVISIBLE (-8050 1775);
FORCEPROP 0 LAST CDS_SEC 1
J 0
(-8050 1775);
DISPLAY 1.021277 (-8050 1775);
DISPLAY INVISIBLE (-8050 1775);
FORCEPROP 1 LASTPIN (-8100 1700) $PN 1
J 0
(-8095 1662);
DISPLAY 0.489362 (-8095 1662);
PAINT MONO (-8095 1662);
FORCEPROP 1 LASTPIN (-8100 1500) $PN 2
J 0
(-8095 1510);
DISPLAY 0.489362 (-8095 1510);
PAINT MONO (-8095 1510);
FORCEPROP 1 LAST WATTAGE 1/8W
J 0
(-8060 1575);
DISPLAY 0.489362 (-8060 1575);
PAINT SKYBLUE (-8060 1575);
FORCEPROP 1 LAST MATERIAL EMPTY
J 0
(-8060 1525);
DISPLAY 0.489362 (-8060 1525);
PAINT RED (-8060 1525);
FORCEPROP 1 LAST TOLERANCE 1%
J 0
(-8055 1625);
DISPLAY 0.489362 (-8055 1625);
PAINT SKYBLUE (-8055 1625);
FORCEPROP 1 LAST VALUE 1.5
J 0
(-8055 1675);
DISPLAY 0.489362 (-8055 1675);
PAINT SKYBLUE (-8055 1675);
FORCEPROP 1 LAST PART_NUMBER CS-1504FB00
J 0
(-8060 1475);
DISPLAY 0.489362 (-8060 1475);
PAINT SKYBLUE (-8060 1475);
FORCEPROP 1 LAST PACK_TYPE 0402LF
J 0
(-8060 1425);
DISPLAY 0.489362 (-8060 1425);
PAINT SKYBLUE (-8060 1425);
FORCEPROP 2 LAST CDS_LIB pure_quanta
J 0
(-8100 1600);
DISPLAY INVISIBLE (-8100 1600);
FORCEPROP 1 LAST PATH I121
J 0
(-8050 1775);
DISPLAY 0.978723 (-8050 1775);
PAINT WHITE (-8050 1775);
DISPLAY INVISIBLE (-8050 1775);
FORCEADD Q_CAP..1
(-8100 2125);
FORCEPROP 1 LAST LOCATION PC163
J 0
(-8050 2225);
DISPLAY 0.489362 (-8050 2225);
PAINT SKYBLUE (-8050 2225);
FORCEPROP 0 LAST $SEC 1
J 0
(-8050 2275);
DISPLAY 0.680851 (-8050 2275);
PAINT MONO (-8050 2275);
DISPLAY INVISIBLE (-8050 2275);
FORCEPROP 0 LAST CDS_SEC 1
J 0
(-8050 2275);
DISPLAY 1.021277 (-8050 2275);
DISPLAY INVISIBLE (-8050 2275);
FORCEPROP 1 LASTPIN (-8100 2225) $PN 1
J 0
(-8090 2205);
DISPLAY 0.489362 (-8090 2205);
PAINT MONO (-8090 2205);
FORCEPROP 1 LASTPIN (-8100 2025) $PN 2
J 0
(-8090 2005);
DISPLAY 0.489362 (-8090 2005);
PAINT MONO (-8090 2005);
FORCEPROP 1 LAST VALUE 560PF
J 0
(-8050 2175);
DISPLAY 0.489362 (-8050 2175);
PAINT SKYBLUE (-8050 2175);
FORCEPROP 1 LAST VOLTAGE 50V
J 0
(-8050 2125);
DISPLAY 0.489362 (-8050 2125);
PAINT SKYBLUE (-8050 2125);
FORCEPROP 1 LAST TOLERANCE 10%
J 0
(-8050 2075);
DISPLAY 0.489362 (-8050 2075);
PAINT SKYBLUE (-8050 2075);
FORCEPROP 1 LAST PACK_TYPE C0402
J 0
(-8050 1925);
DISPLAY 0.489362 (-8050 1925);
PAINT SKYBLUE (-8050 1925);
FORCEPROP 1 LAST MATERIAL EMPTY
J 0
(-8050 2025);
DISPLAY 0.489362 (-8050 2025);
PAINT RED (-8050 2025);
FORCEPROP 1 LAST PART_NUMBER CH1566K1B09
J 0
(-8050 1975);
DISPLAY 0.489362 (-8050 1975);
PAINT SKYBLUE (-8050 1975);
FORCEPROP 2 LAST CDS_LIB pure_quanta
J 0
(-8100 2125);
DISPLAY INVISIBLE (-8100 2125);
FORCEPROP 1 LAST PATH I122
J 0
(-8050 2275);
DISPLAY 0.978723 (-8050 2275);
PAINT WHITE (-8050 2275);
DISPLAY INVISIBLE (-8050 2275);
FORCEADD VCC_CORE..1
(-11175 6400);
FORCEPROP 3 LASTPIN (-11175 6350) SIG_NAME PVDDCR_CPU1_P0_PVCC\g
J 0
(-11165 6360);
DISPLAY 0.659574 (-11165 6360);
PAINT MONO (-11165 6360);
DISPLAY INVISIBLE (-11165 6360);
FORCEPROP 1 LAST HDL_POWER PVDDCR_CPU1_P0_PVCC
J 1
(-11175 6450);
DISPLAY 0.489362 (-11175 6450);
PAINT GREEN (-11175 6450);
FORCEPROP 2 LAST CDS_LIB pure_quanta_power
J 0
(-11175 6400);
DISPLAY INVISIBLE (-11175 6400);
FORCEPROP 1 LAST PATH I123
J 0
(-11125 6425);
DISPLAY 0.872340 (-11125 6425);
PAINT AQUA (-11125 6425);
DISPLAY INVISIBLE (-11125 6425);
FORCEADD VCC_CORE..1
(-11200 3700);
FORCEPROP 3 LASTPIN (-11200 3650) SIG_NAME PVDDCR_CPU1_P0_PVCC\g
J 0
(-11190 3660);
DISPLAY 0.659574 (-11190 3660);
PAINT MONO (-11190 3660);
DISPLAY INVISIBLE (-11190 3660);
FORCEPROP 1 LAST HDL_POWER PVDDCR_CPU1_P0_PVCC
J 1
(-11200 3750);
DISPLAY 0.489362 (-11200 3750);
PAINT GREEN (-11200 3750);
FORCEPROP 2 LAST CDS_LIB pure_quanta_power
J 0
(-11200 3700);
DISPLAY INVISIBLE (-11200 3700);
FORCEPROP 1 LAST PATH I124
J 0
(-11150 3725);
DISPLAY 0.872340 (-11150 3725);
PAINT AQUA (-11150 3725);
DISPLAY INVISIBLE (-11150 3725);
FORCEADD Q_INDUCTOR..1
R 2
(-7450 2100);
FORCEPROP 1 LAST LOCATION PL16
J 2
(-7550 2275);
DISPLAY 0.574468 (-7550 2275);
PAINT SKYBLUE (-7550 2275);
FORCEPROP 0 LAST $SEC 1
J 0
(-7550 2325);
DISPLAY 0.680851 (-7550 2325);
PAINT MONO (-7550 2325);
DISPLAY INVISIBLE (-7550 2325);
FORCEPROP 0 LAST CDS_SEC 1
J 0
(-7650 2275);
DISPLAY 1.021277 (-7650 2275);
DISPLAY INVISIBLE (-7650 2275);
FORCEPROP 0 LASTPIN (-7350 2075) $PN 1
J 0
(-7340 2085);
DISPLAY 0.680851 (-7340 2085);
PAINT MONO (-7340 2085);
FORCEPROP 0 LASTPIN (-7550 2075) $PN 2
J 2
(-7560 2085);
DISPLAY 0.680851 (-7560 2085);
PAINT MONO (-7560 2085);
FORCEPROP 2 LAST VALUE 0.22UH/33A
J 0
(-7650 2200);
DISPLAY 0.489362 (-7650 2200);
PAINT SKYBLUE (-7650 2200);
FORCEPROP 2 LAST PACK_TYPE SMLF
J 0
(-7650 2225);
DISPLAY 0.489362 (-7650 2225);
FORCEPROP 1 LAST MATERIAL IND
J 2
(-7575 2150);
DISPLAY 0.468085 (-7575 2150);
PAINT SKYBLUE (-7575 2150);
FORCEPROP 1 LAST PART_NUMBER CV+22Y0EZ00
J 2
(-7400 2175);
DISPLAY 0.468085 (-7400 2175);
PAINT SKYBLUE (-7400 2175);
FORCEPROP 1 LAST NEEDS_NO_SIZE TRUE
J 2
(-7450 2100);
DISPLAY 0.468085 (-7450 2100);
PAINT GREEN (-7450 2100);
DISPLAY INVISIBLE (-7450 2100);
FORCEPROP 1 LAST PATH I125
J 2
(-7525 2155);
DISPLAY 0.723404 (-7525 2155);
PAINT GREEN (-7525 2155);
DISPLAY INVISIBLE (-7525 2155);
FORCEPROP 2 LAST CDS_LIB pure_quanta
J 0
(-7450 2100);
DISPLAY INVISIBLE (-7450 2100);
FORCEADD UNIVERSAL_GND..1
(-7675 1975);
FORCEPROP 3 LASTPIN (-7675 2025) SIG_NAME GND\g
J 0
(-7665 2035);
DISPLAY 0.659574 (-7665 2035);
PAINT MONO (-7665 2035);
DISPLAY INVISIBLE (-7665 2035);
FORCEPROP 2 LAST CDS_LIB pure_quanta_power
J 0
(-7675 1975);
DISPLAY INVISIBLE (-7675 1975);
FORCEPROP 1 LAST PATH I126
J 0
(-7600 1975);
DISPLAY 0.872340 (-7600 1975);
PAINT AQUA (-7600 1975);
DISPLAY INVISIBLE (-7600 1975);
FORCEPROP 1 LAST HDL_POWER GND
J 1
(-7650 1900);
DISPLAY 0.872340 (-7650 1900);
PAINT GREEN (-7650 1900);
DISPLAY INVISIBLE (-7650 1900);
FORCEADD OFFPAGE..3
(-5425 2075);
FORCEPROP 2 LAST $XR0 182 
J 0
(-5211 2075);
DISPLAY 0.638298 (-5211 2075);
PAINT MONO (-5211 2075);
FORCEPROP 1 LAST OFFPAGE TRUE
J 0
(-5100 1950);
DISPLAY 0.872340 (-5100 1950);
PAINT GREEN (-5100 1950);
DISPLAY INVISIBLE (-5100 1950);
FORCEPROP 1 LAST COMMENT_BODY TRUE
J 0
(-5475 1975);
DISPLAY 0.872340 (-5475 1975);
PAINT GREEN (-5475 1975);
DISPLAY INVISIBLE (-5475 1975);
FORCEPROP 2 LAST PATH I127
J 0
(-5225 2150);
DISPLAY 1.021277 (-5225 2150);
DISPLAY INVISIBLE (-5225 2150);
FORCEPROP 2 LAST CDS_LIB standard
J 0
(-5425 2075);
DISPLAY INVISIBLE (-5425 2075);
FORCEADD UNIVERSAL_GND..1
(-11500 4450);
FORCEPROP 3 LASTPIN (-11500 4500) SIG_NAME GND\g
J 0
(-11490 4510);
DISPLAY 0.659574 (-11490 4510);
PAINT MONO (-11490 4510);
DISPLAY INVISIBLE (-11490 4510);
FORCEPROP 2 LAST CDS_LIB pure_quanta_power
J 0
(-11500 4450);
PAINT MONO (-11500 4450);
DISPLAY INVISIBLE (-11500 4450);
FORCEPROP 1 LAST PATH I14
J 0
(-11425 4450);
DISPLAY 0.872340 (-11425 4450);
PAINT AQUA (-11425 4450);
DISPLAY INVISIBLE (-11425 4450);
FORCEPROP 1 LAST HDL_POWER GND
J 1
(-11475 4375);
DISPLAY 0.872340 (-11475 4375);
PAINT GREEN (-11475 4375);
DISPLAY INVISIBLE (-11475 4375);
FORCEADD Q_RES..2
R 2
(-11500 4675);
FORCEPROP 1 LAST LOCATION PR106
J 2
(-11545 4800);
DISPLAY 0.489362 (-11545 4800);
PAINT SKYBLUE (-11545 4800);
FORCEPROP 0 LAST $SEC 1
J 2
(-11550 4850);
DISPLAY 0.680851 (-11550 4850);
PAINT MONO (-11550 4850);
DISPLAY INVISIBLE (-11550 4850);
FORCEPROP 0 LAST CDS_SEC 1
J 2
(-11550 4850);
DISPLAY 1.021277 (-11550 4850);
DISPLAY INVISIBLE (-11550 4850);
FORCEPROP 1 LASTPIN (-11500 4775) $PN 1
J 2
(-11505 4737);
DISPLAY 0.489362 (-11505 4737);
PAINT MONO (-11505 4737);
FORCEPROP 1 LASTPIN (-11500 4575) $PN 2
J 2
(-11505 4585);
DISPLAY 0.489362 (-11505 4585);
PAINT MONO (-11505 4585);
FORCEPROP 1 LAST WATTAGE 1/16W
J 2
(-11550 4650);
DISPLAY 0.489362 (-11550 4650);
PAINT SKYBLUE (-11550 4650);
FORCEPROP 1 LAST MATERIAL EMPTY
J 2
(-11550 4600);
DISPLAY 0.489362 (-11550 4600);
PAINT RED (-11550 4600);
FORCEPROP 1 LAST TOLERANCE 1%
J 2
(-11555 4700);
DISPLAY 0.489362 (-11555 4700);
PAINT SKYBLUE (-11555 4700);
FORCEPROP 1 LAST VALUE 8.87K
J 2
(-11555 4750);
DISPLAY 0.489362 (-11555 4750);
PAINT SKYBLUE (-11555 4750);
FORCEPROP 1 LAST PART_NUMBER CS28872FB01
J 2
(-11550 4550);
DISPLAY 0.489362 (-11550 4550);
PAINT SKYBLUE (-11550 4550);
FORCEPROP 1 LAST PACK_TYPE 0402LF
J 2
(-11550 4500);
DISPLAY 0.489362 (-11550 4500);
PAINT SKYBLUE (-11550 4500);
FORCEPROP 2 LAST CDS_LIB pure_quanta
J 2
(-11500 4675);
DISPLAY INVISIBLE (-11500 4675);
FORCEPROP 1 LAST PATH I15
J 2
(-11550 4850);
DISPLAY 0.978723 (-11550 4850);
PAINT WHITE (-11550 4850);
DISPLAY INVISIBLE (-11550 4850);
FORCEADD Q_RES..2
R 2
(-11525 1825);
FORCEPROP 1 LAST LOCATION PR105
J 2
(-11570 1950);
DISPLAY 0.489362 (-11570 1950);
PAINT SKYBLUE (-11570 1950);
FORCEPROP 0 LAST $SEC 1
J 2
(-11575 2000);
DISPLAY 0.680851 (-11575 2000);
PAINT MONO (-11575 2000);
DISPLAY INVISIBLE (-11575 2000);
FORCEPROP 0 LAST CDS_SEC 1
J 2
(-11575 2000);
DISPLAY 1.021277 (-11575 2000);
DISPLAY INVISIBLE (-11575 2000);
FORCEPROP 1 LASTPIN (-11525 1925) $PN 1
J 2
(-11530 1887);
DISPLAY 0.489362 (-11530 1887);
PAINT MONO (-11530 1887);
FORCEPROP 1 LASTPIN (-11525 1725) $PN 2
J 2
(-11530 1735);
DISPLAY 0.489362 (-11530 1735);
PAINT MONO (-11530 1735);
FORCEPROP 1 LAST WATTAGE 1/16W
J 2
(-11575 1800);
DISPLAY 0.489362 (-11575 1800);
PAINT SKYBLUE (-11575 1800);
FORCEPROP 1 LAST MATERIAL EMPTY
J 2
(-11575 1750);
DISPLAY 0.489362 (-11575 1750);
PAINT RED (-11575 1750);
FORCEPROP 1 LAST TOLERANCE 1%
J 2
(-11580 1850);
DISPLAY 0.489362 (-11580 1850);
PAINT SKYBLUE (-11580 1850);
FORCEPROP 1 LAST VALUE 8.87K
J 2
(-11580 1900);
DISPLAY 0.489362 (-11580 1900);
PAINT SKYBLUE (-11580 1900);
FORCEPROP 1 LAST PART_NUMBER CS28872FB01
J 2
(-11575 1700);
DISPLAY 0.489362 (-11575 1700);
PAINT SKYBLUE (-11575 1700);
FORCEPROP 1 LAST PACK_TYPE 0402LF
J 2
(-11575 1650);
DISPLAY 0.489362 (-11575 1650);
PAINT SKYBLUE (-11575 1650);
FORCEPROP 2 LAST CDS_LIB pure_quanta
J 2
(-11525 1825);
DISPLAY INVISIBLE (-11525 1825);
FORCEPROP 1 LAST PATH I2
J 2
(-11575 2000);
DISPLAY 0.978723 (-11575 2000);
PAINT WHITE (-11575 2000);
DISPLAY INVISIBLE (-11575 2000);
FORCEADD OFFPAGE..1
(-11025 4525);
FORCEPROP 2 LAST $XR0 176 
J 0
(-11277 4525);
DISPLAY 0.638298 (-11277 4525);
PAINT MONO (-11277 4525);
FORCEPROP 2 LAST CDS_LIB standard
J 0
(-11025 4525);
DISPLAY INVISIBLE (-11025 4525);
FORCEPROP 1 LAST OFFPAGE TRUE
J 0
(-10700 4400);
DISPLAY 0.872340 (-10700 4400);
PAINT GREEN (-10700 4400);
DISPLAY INVISIBLE (-10700 4400);
FORCEPROP 1 LAST COMMENT_BODY TRUE
J 0
(-10900 4425);
DISPLAY 0.872340 (-10900 4425);
PAINT GREEN (-10900 4425);
DISPLAY INVISIBLE (-10900 4425);
FORCEPROP 2 LAST PATH I21
J 0
(-11275 4575);
DISPLAY 1.021277 (-11275 4575);
DISPLAY INVISIBLE (-11275 4575);
FORCEADD OFFPAGE..5
(-11025 4625);
FORCEPROP 2 LAST $XR2 176 
J 0
(-11310 4661);
DISPLAY 0.638298 (-11310 4661);
PAINT MONO (-11310 4661);
FORCEPROP 2 LAST $XR1 182 
J 0
(-11310 4589);
DISPLAY 0.638298 (-11310 4589);
PAINT MONO (-11310 4589);
FORCEPROP 2 LAST $XR0 181 
J 0
(-11310 4625);
DISPLAY 0.638298 (-11310 4625);
PAINT MONO (-11310 4625);
FORCEPROP 2 LAST CDS_LIB standard
J 0
(-11025 4625);
DISPLAY INVISIBLE (-11025 4625);
FORCEPROP 1 LAST OFFPAGE TRUE
J 0
(-10700 4500);
DISPLAY 0.872340 (-10700 4500);
PAINT GREEN (-10700 4500);
DISPLAY INVISIBLE (-10700 4500);
FORCEPROP 1 LAST COMMENT_BODY TRUE
J 0
(-10925 4550);
DISPLAY 0.872340 (-10925 4550);
PAINT GREEN (-10925 4550);
DISPLAY INVISIBLE (-10925 4550);
FORCEPROP 2 LAST PATH I22
J 0
(-11300 4800);
DISPLAY 1.021277 (-11300 4800);
DISPLAY INVISIBLE (-11300 4800);
FORCEADD ISL99390FRZTR5935..1
(-9500 2325);
FORCEPROP 1 LAST LOCATION PU20
J 0
(-9800 3200);
DISPLAY 0.489362 (-9800 3200);
PAINT SKYBLUE (-9800 3200);
FORCEPROP 0 LAST $SEC 1
J 0
(-9800 3375);
DISPLAY 0.680851 (-9800 3375);
PAINT MONO (-9800 3375);
DISPLAY INVISIBLE (-9800 3375);
FORCEPROP 2 LAST CDS_SEC 1
J 0
(-9750 3325);
DISPLAY 1.021277 (-9750 3325);
DISPLAY INVISIBLE (-9750 3325);
FORCEPROP 0 LASTPIN (-9100 1875) $PN 2
J 0
(-9090 1885);
DISPLAY 0.489362 (-9090 1885);
PAINT MONO (-9090 1885);
FORCEPROP 0 LASTPIN (-9100 2675) $PN 33
J 0
(-9090 2685);
DISPLAY 0.489362 (-9090 2685);
PAINT MONO (-9090 2685);
FORCEPROP 0 LASTPIN (-9950 2075) $PN 31
J 2
(-9960 2085);
DISPLAY 0.489362 (-9960 2085);
PAINT MONO (-9960 2085);
FORCEPROP 0 LASTPIN (-9950 2475) $PN 35
J 2
(-9960 2485);
DISPLAY 0.489362 (-9960 2485);
PAINT MONO (-9960 2485);
FORCEPROP 0 LASTPIN (-9100 2025) $PN 6
J 0
(-9090 2035);
DISPLAY 0.489362 (-9090 2035);
PAINT MONO (-9090 2035);
FORCEPROP 0 LASTPIN (-9100 1975) $PN 41
J 0
(-9090 1985);
DISPLAY 0.489362 (-9090 1985);
PAINT MONO (-9090 1985);
FORCEPROP 0 LASTPIN (-9950 2325) $PN 38
J 2
(-9960 2335);
DISPLAY 0.489362 (-9960 2335);
PAINT MONO (-9960 2335);
FORCEPROP 0 LASTPIN (-9950 2025) $PN 37
J 2
(-9960 2035);
DISPLAY 0.489362 (-9960 2035);
PAINT MONO (-9960 2035);
FORCEPROP 0 LASTPIN (-9100 1825) $PN 5
J 0
(-9090 1835);
DISPLAY 0.489362 (-9090 1835);
PAINT MONO (-9090 1835);
FORCEPROP 0 LASTPIN (-9100 1775) $PN 7_9-20_24
J 0
(-9090 1785);
DISPLAY 0.489362 (-9090 1785);
PAINT MONO (-9090 1785);
FORCEPROP 0 LASTPIN (-9100 1725) $PN 40
J 0
(-9090 1735);
DISPLAY 0.489362 (-9090 1735);
PAINT MONO (-9090 1735);
FORCEPROP 0 LASTPIN (-9100 2425) $PN 32
J 0
(-9090 2435);
DISPLAY 0.489362 (-9090 2435);
PAINT MONO (-9090 2435);
FORCEPROP 0 LASTPIN (-9950 2975) $PN 4
J 2
(-9960 2985);
DISPLAY 0.489362 (-9960 2985);
PAINT MONO (-9960 2985);
FORCEPROP 0 LASTPIN (-9950 1725) $PN 34
J 2
(-9960 1735);
DISPLAY 0.489362 (-9960 1735);
PAINT MONO (-9960 1735);
FORCEPROP 0 LASTPIN (-9950 2225) $PN 39
J 2
(-9960 2235);
DISPLAY 0.489362 (-9960 2235);
PAINT MONO (-9960 2235);
FORCEPROP 0 LASTPIN (-9100 2325) $PN 10_19
J 0
(-9090 2335);
DISPLAY 0.489362 (-9090 2335);
PAINT MONO (-9090 2335);
FORCEPROP 0 LASTPIN (-9950 1825) $PN 36
J 2
(-9960 1835);
DISPLAY 0.489362 (-9960 1835);
PAINT MONO (-9960 1835);
FORCEPROP 0 LASTPIN (-9950 2675) $PN 3
J 2
(-9960 2685);
DISPLAY 0.489362 (-9960 2685);
PAINT MONO (-9960 2685);
FORCEPROP 0 LASTPIN (-9100 2975) $PN 25_29
J 0
(-9090 2985);
DISPLAY 0.489362 (-9090 2985);
PAINT MONO (-9090 2985);
FORCEPROP 0 LASTPIN (-9100 2925) $PN 30
J 0
(-9090 2935);
DISPLAY 0.489362 (-9090 2935);
PAINT MONO (-9090 2935);
FORCEPROP 0 LASTPIN (-9100 2075) $PN 1
J 0
(-9090 2085);
DISPLAY 0.489362 (-9090 2085);
PAINT MONO (-9090 2085);
FORCEPROP 2 LAST PART_TYPE SMLF
J 0
(-9800 3325);
DISPLAY 0.638298 (-9800 3325);
FORCEPROP 1 LAST MATERIAL IC
J 0
(-9800 3050);
DISPLAY 0.489362 (-9800 3050);
PAINT SKYBLUE (-9800 3050);
FORCEPROP 2 LAST VALUE ISL99390FRZ-TR5935
J 0
(-9800 3275);
DISPLAY 0.489362 (-9800 3275);
PAINT SKYBLUE (-9800 3275);
FORCEPROP 1 LAST PART_NUMBER AL099390004
J 0
(-9800 3125);
DISPLAY 0.489362 (-9800 3125);
PAINT SKYBLUE (-9800 3125);
FORCEPROP 2 LAST CDS_LIB pure_quanta
J 0
(-9500 2325);
DISPLAY INVISIBLE (-9500 2325);
FORCEPROP 1 LAST CDS_LMAN_SYM_OUTLINE -300,700,250,-650
J 0
(-9500 2325);
DISPLAY 0.468085 (-9500 2325);
PAINT GREEN (-9500 2325);
DISPLAY INVISIBLE (-9500 2325);
FORCEPROP 1 LAST NEEDS_NO_SIZE TRUE
J 0
(-9500 2325);
DISPLAY 0.723404 (-9500 2325);
PAINT GREEN (-9500 2325);
DISPLAY INVISIBLE (-9500 2325);
FORCEPROP 1 LAST PATH I23
J 0
(-9500 2325);
DISPLAY 0.723404 (-9500 2325);
PAINT GREEN (-9500 2325);
DISPLAY INVISIBLE (-9500 2325);
FORCEADD UNIVERSAL_GND..1
(-8850 1600);
FORCEPROP 3 LASTPIN (-8850 1650) SIG_NAME GND\g
J 0
(-8840 1660);
DISPLAY 0.659574 (-8840 1660);
PAINT MONO (-8840 1660);
DISPLAY INVISIBLE (-8840 1660);
FORCEPROP 2 LAST CDS_LIB pure_quanta_power
J 0
(-8850 1600);
PAINT MONO (-8850 1600);
DISPLAY INVISIBLE (-8850 1600);
FORCEPROP 1 LAST PATH I24
J 0
(-8775 1600);
DISPLAY 0.872340 (-8775 1600);
PAINT AQUA (-8775 1600);
DISPLAY INVISIBLE (-8775 1600);
FORCEPROP 1 LAST HDL_POWER GND
J 1
(-8825 1525);
DISPLAY 0.872340 (-8825 1525);
PAINT GREEN (-8825 1525);
DISPLAY INVISIBLE (-8825 1525);
FORCEADD ISL99390FRZTR5935..1
(-9500 5125);
FORCEPROP 1 LAST LOCATION PU19
J 0
(-9800 6000);
DISPLAY 0.489362 (-9800 6000);
PAINT SKYBLUE (-9800 6000);
FORCEPROP 0 LAST $SEC 1
J 0
(-9800 6200);
DISPLAY 0.680851 (-9800 6200);
PAINT MONO (-9800 6200);
DISPLAY INVISIBLE (-9800 6200);
FORCEPROP 2 LAST CDS_SEC 1
J 0
(-9750 6125);
DISPLAY 1.021277 (-9750 6125);
DISPLAY INVISIBLE (-9750 6125);
FORCEPROP 0 LASTPIN (-9100 4675) $PN 2
J 0
(-9090 4685);
DISPLAY 0.489362 (-9090 4685);
PAINT MONO (-9090 4685);
FORCEPROP 0 LASTPIN (-9100 5475) $PN 33
J 0
(-9090 5485);
DISPLAY 0.489362 (-9090 5485);
PAINT MONO (-9090 5485);
FORCEPROP 0 LASTPIN (-9950 4875) $PN 31
J 2
(-9960 4885);
DISPLAY 0.489362 (-9960 4885);
PAINT MONO (-9960 4885);
FORCEPROP 0 LASTPIN (-9950 5275) $PN 35
J 2
(-9960 5285);
DISPLAY 0.489362 (-9960 5285);
PAINT MONO (-9960 5285);
FORCEPROP 0 LASTPIN (-9100 4825) $PN 6
J 0
(-9090 4835);
DISPLAY 0.489362 (-9090 4835);
PAINT MONO (-9090 4835);
FORCEPROP 0 LASTPIN (-9100 4775) $PN 41
J 0
(-9090 4785);
DISPLAY 0.489362 (-9090 4785);
PAINT MONO (-9090 4785);
FORCEPROP 0 LASTPIN (-9950 5125) $PN 38
J 2
(-9960 5135);
DISPLAY 0.489362 (-9960 5135);
PAINT MONO (-9960 5135);
FORCEPROP 0 LASTPIN (-9950 4825) $PN 37
J 2
(-9960 4835);
DISPLAY 0.489362 (-9960 4835);
PAINT MONO (-9960 4835);
FORCEPROP 0 LASTPIN (-9100 4625) $PN 5
J 0
(-9090 4635);
DISPLAY 0.489362 (-9090 4635);
PAINT MONO (-9090 4635);
FORCEPROP 0 LASTPIN (-9100 4575) $PN 7_9-20_24
J 0
(-9090 4585);
DISPLAY 0.489362 (-9090 4585);
PAINT MONO (-9090 4585);
FORCEPROP 0 LASTPIN (-9100 4525) $PN 40
J 0
(-9090 4535);
DISPLAY 0.489362 (-9090 4535);
PAINT MONO (-9090 4535);
FORCEPROP 0 LASTPIN (-9100 5225) $PN 32
J 0
(-9090 5235);
DISPLAY 0.489362 (-9090 5235);
PAINT MONO (-9090 5235);
FORCEPROP 0 LASTPIN (-9950 5775) $PN 4
J 2
(-9960 5785);
DISPLAY 0.489362 (-9960 5785);
PAINT MONO (-9960 5785);
FORCEPROP 0 LASTPIN (-9950 4525) $PN 34
J 2
(-9960 4535);
DISPLAY 0.489362 (-9960 4535);
PAINT MONO (-9960 4535);
FORCEPROP 0 LASTPIN (-9950 5025) $PN 39
J 2
(-9960 5035);
DISPLAY 0.489362 (-9960 5035);
PAINT MONO (-9960 5035);
FORCEPROP 0 LASTPIN (-9100 5125) $PN 10_19
J 0
(-9090 5135);
DISPLAY 0.489362 (-9090 5135);
PAINT MONO (-9090 5135);
FORCEPROP 0 LASTPIN (-9950 4625) $PN 36
J 2
(-9960 4635);
DISPLAY 0.489362 (-9960 4635);
PAINT MONO (-9960 4635);
FORCEPROP 0 LASTPIN (-9950 5475) $PN 3
J 2
(-9960 5485);
DISPLAY 0.489362 (-9960 5485);
PAINT MONO (-9960 5485);
FORCEPROP 0 LASTPIN (-9100 5775) $PN 25_29
J 0
(-9090 5785);
DISPLAY 0.489362 (-9090 5785);
PAINT MONO (-9090 5785);
FORCEPROP 0 LASTPIN (-9100 5725) $PN 30
J 0
(-9090 5735);
DISPLAY 0.489362 (-9090 5735);
PAINT MONO (-9090 5735);
FORCEPROP 0 LASTPIN (-9100 4875) $PN 1
J 0
(-9090 4885);
DISPLAY 0.489362 (-9090 4885);
PAINT MONO (-9090 4885);
FORCEPROP 2 LAST PART_TYPE SMLF
J 0
(-9800 6150);
DISPLAY 0.638298 (-9800 6150);
FORCEPROP 1 LAST MATERIAL IC
J 0
(-9800 5850);
DISPLAY 0.489362 (-9800 5850);
PAINT SKYBLUE (-9800 5850);
FORCEPROP 2 LAST VALUE ISL99390FRZ-TR5935
J 0
(-9800 6100);
DISPLAY 0.489362 (-9800 6100);
PAINT SKYBLUE (-9800 6100);
FORCEPROP 1 LAST PART_NUMBER AL099390004
J 0
(-9800 5925);
DISPLAY 0.489362 (-9800 5925);
PAINT SKYBLUE (-9800 5925);
FORCEPROP 1 LAST CDS_LMAN_SYM_OUTLINE -300,700,250,-650
J 0
(-9500 5125);
DISPLAY 0.468085 (-9500 5125);
PAINT GREEN (-9500 5125);
DISPLAY INVISIBLE (-9500 5125);
FORCEPROP 1 LAST NEEDS_NO_SIZE TRUE
J 0
(-9500 5125);
DISPLAY 0.723404 (-9500 5125);
PAINT GREEN (-9500 5125);
DISPLAY INVISIBLE (-9500 5125);
FORCEPROP 2 LAST CDS_LIB pure_quanta
J 0
(-9500 5125);
DISPLAY INVISIBLE (-9500 5125);
FORCEPROP 1 LAST PATH I26
J 0
(-9500 5125);
DISPLAY 0.723404 (-9500 5125);
PAINT GREEN (-9500 5125);
DISPLAY INVISIBLE (-9500 5125);
FORCEADD Q_CAP..1
(-8150 3275);
FORCEPROP 1 LAST LOCATION PC180_4
J 0
(-8100 3425);
DISPLAY 0.489362 (-8100 3425);
PAINT SKYBLUE (-8100 3425);
FORCEPROP 0 LAST $SEC 1
J 0
(-8100 3475);
DISPLAY 0.680851 (-8100 3475);
PAINT MONO (-8100 3475);
DISPLAY INVISIBLE (-8100 3475);
FORCEPROP 0 LAST CDS_SEC 1
J 0
(-8100 3475);
DISPLAY 1.021277 (-8100 3475);
DISPLAY INVISIBLE (-8100 3475);
FORCEPROP 1 LASTPIN (-8150 3375) $PN 1
J 0
(-8140 3355);
DISPLAY 0.489362 (-8140 3355);
PAINT MONO (-8140 3355);
FORCEPROP 1 LASTPIN (-8150 3175) $PN 2
J 0
(-8140 3155);
DISPLAY 0.489362 (-8140 3155);
PAINT MONO (-8140 3155);
FORCEPROP 1 LAST MATERIAL X6S
J 0
(-8100 3225);
DISPLAY 0.489362 (-8100 3225);
PAINT SKYBLUE (-8100 3225);
FORCEPROP 1 LAST TOLERANCE 10%
J 0
(-8100 3275);
DISPLAY 0.489362 (-8100 3275);
PAINT SKYBLUE (-8100 3275);
FORCEPROP 1 LAST VALUE 1UF
J 0
(-8100 3375);
DISPLAY 0.489362 (-8100 3375);
PAINT SKYBLUE (-8100 3375);
FORCEPROP 1 LAST VOLTAGE 25V
J 0
(-8100 3325);
DISPLAY 0.489362 (-8100 3325);
PAINT SKYBLUE (-8100 3325);
FORCEPROP 1 LAST PART_NUMBER CH5104KEB02
J 0
(-8100 3125);
DISPLAY 0.489362 (-8100 3125);
PAINT SKYBLUE (-8100 3125);
FORCEPROP 1 LAST PACK_TYPE C0402
J 0
(-8100 3175);
DISPLAY 0.489362 (-8100 3175);
PAINT SKYBLUE (-8100 3175);
FORCEPROP 2 LAST CDS_LIB pure_quanta
J 0
(-8150 3275);
DISPLAY INVISIBLE (-8150 3275);
FORCEPROP 1 LAST PATH I28
J 0
(-8100 3425);
DISPLAY 0.978723 (-8100 3425);
PAINT WHITE (-8100 3425);
DISPLAY INVISIBLE (-8100 3425);
FORCEADD UNIVERSAL_GND..1
(-8850 4400);
FORCEPROP 3 LASTPIN (-8850 4450) SIG_NAME GND\g
J 0
(-8840 4460);
DISPLAY 0.659574 (-8840 4460);
PAINT MONO (-8840 4460);
DISPLAY INVISIBLE (-8840 4460);
FORCEPROP 2 LAST CDS_LIB pure_quanta_power
J 0
(-8850 4400);
PAINT MONO (-8850 4400);
DISPLAY INVISIBLE (-8850 4400);
FORCEPROP 1 LAST PATH I29
J 0
(-8775 4400);
DISPLAY 0.872340 (-8775 4400);
PAINT AQUA (-8775 4400);
DISPLAY INVISIBLE (-8775 4400);
FORCEPROP 1 LAST HDL_POWER GND
J 1
(-8825 4325);
DISPLAY 0.872340 (-8825 4325);
PAINT GREEN (-8825 4325);
DISPLAY INVISIBLE (-8825 4325);
FORCEADD OFFPAGE..1
(-11025 5025);
FORCEPROP 2 LAST $XR5 182 
J 0
(-11877 5025);
DISPLAY 0.638298 (-11877 5025);
PAINT MONO (-11877 5025);
FORCEPROP 2 LAST $XR4 181 
J 0
(-11757 5025);
DISPLAY 0.638298 (-11757 5025);
PAINT MONO (-11757 5025);
FORCEPROP 2 LAST $XR3 179 
J 0
(-11637 5025);
DISPLAY 0.638298 (-11637 5025);
PAINT MONO (-11637 5025);
FORCEPROP 2 LAST $XR2 178 
J 0
(-11517 5025);
DISPLAY 0.638298 (-11517 5025);
PAINT MONO (-11517 5025);
FORCEPROP 2 LAST $XR1 177 
J 0
(-11397 5025);
DISPLAY 0.638298 (-11397 5025);
PAINT MONO (-11397 5025);
FORCEPROP 2 LAST $XR0 176 
J 0
(-11277 5025);
DISPLAY 0.638298 (-11277 5025);
PAINT MONO (-11277 5025);
FORCEPROP 2 LAST CDS_LIB standard
J 0
(-11025 5025);
DISPLAY INVISIBLE (-11025 5025);
FORCEPROP 1 LAST OFFPAGE TRUE
J 0
(-10700 4900);
DISPLAY 0.872340 (-10700 4900);
PAINT GREEN (-10700 4900);
DISPLAY INVISIBLE (-10700 4900);
FORCEPROP 1 LAST COMMENT_BODY TRUE
J 0
(-10900 4925);
DISPLAY 0.872340 (-10900 4925);
PAINT GREEN (-10900 4925);
DISPLAY INVISIBLE (-10900 4925);
FORCEPROP 2 LAST PATH I33
J 0
(-11275 5075);
DISPLAY 1.021277 (-11275 5075);
DISPLAY INVISIBLE (-11275 5075);
FORCEADD OFFPAGE..5
(-11025 5125);
FORCEPROP 2 LAST $XR0 176 
J 0
(-11310 5125);
DISPLAY 0.638298 (-11310 5125);
PAINT MONO (-11310 5125);
FORCEPROP 2 LAST CDS_LIB standard
J 0
(-11025 5125);
DISPLAY INVISIBLE (-11025 5125);
FORCEPROP 1 LAST OFFPAGE TRUE
J 0
(-10700 5000);
DISPLAY 0.872340 (-10700 5000);
PAINT GREEN (-10700 5000);
DISPLAY INVISIBLE (-10700 5000);
FORCEPROP 1 LAST COMMENT_BODY TRUE
J 0
(-10925 5050);
DISPLAY 0.872340 (-10925 5050);
PAINT GREEN (-10925 5050);
DISPLAY INVISIBLE (-10925 5050);
FORCEPROP 2 LAST PATH I34
J 0
(-11300 5175);
DISPLAY 1.021277 (-11300 5175);
DISPLAY INVISIBLE (-11300 5175);
FORCEADD OFFPAGE..1
(-11050 1725);
FORCEPROP 2 LAST $XR0 176 
J 0
(-11302 1725);
DISPLAY 0.638298 (-11302 1725);
PAINT MONO (-11302 1725);
FORCEPROP 2 LAST CDS_LIB standard
J 0
(-11050 1725);
DISPLAY INVISIBLE (-11050 1725);
FORCEPROP 1 LAST OFFPAGE TRUE
J 0
(-10725 1600);
DISPLAY 0.872340 (-10725 1600);
PAINT GREEN (-10725 1600);
DISPLAY INVISIBLE (-10725 1600);
FORCEPROP 1 LAST COMMENT_BODY TRUE
J 0
(-10925 1625);
DISPLAY 0.872340 (-10925 1625);
PAINT GREEN (-10925 1625);
DISPLAY INVISIBLE (-10925 1625);
FORCEPROP 2 LAST PATH I4
J 0
(-11300 1775);
DISPLAY 1.021277 (-11300 1775);
DISPLAY INVISIBLE (-11300 1775);
FORCEADD Q_CAP..1
(-8225 6075);
FORCEPROP 1 LAST LOCATION PC179_3
J 0
(-8175 6225);
DISPLAY 0.489362 (-8175 6225);
PAINT SKYBLUE (-8175 6225);
FORCEPROP 0 LAST $SEC 1
J 0
(-8175 6275);
DISPLAY 0.680851 (-8175 6275);
PAINT MONO (-8175 6275);
DISPLAY INVISIBLE (-8175 6275);
FORCEPROP 0 LAST CDS_SEC 1
J 0
(-8175 6275);
DISPLAY 1.021277 (-8175 6275);
DISPLAY INVISIBLE (-8175 6275);
FORCEPROP 1 LASTPIN (-8225 6175) $PN 1
J 0
(-8215 6155);
DISPLAY 0.489362 (-8215 6155);
PAINT MONO (-8215 6155);
FORCEPROP 1 LASTPIN (-8225 5975) $PN 2
J 0
(-8215 5955);
DISPLAY 0.489362 (-8215 5955);
PAINT MONO (-8215 5955);
FORCEPROP 1 LAST MATERIAL X6S
J 0
(-8175 6025);
DISPLAY 0.489362 (-8175 6025);
PAINT SKYBLUE (-8175 6025);
FORCEPROP 1 LAST TOLERANCE 10%
J 0
(-8175 6075);
DISPLAY 0.489362 (-8175 6075);
PAINT SKYBLUE (-8175 6075);
FORCEPROP 1 LAST VALUE 1UF
J 0
(-8175 6175);
DISPLAY 0.489362 (-8175 6175);
PAINT SKYBLUE (-8175 6175);
FORCEPROP 1 LAST PART_NUMBER CH5104KEB02
J 0
(-8175 5925);
DISPLAY 0.489362 (-8175 5925);
PAINT SKYBLUE (-8175 5925);
FORCEPROP 1 LAST VOLTAGE 25V
J 0
(-8175 6125);
DISPLAY 0.489362 (-8175 6125);
PAINT SKYBLUE (-8175 6125);
FORCEPROP 1 LAST PACK_TYPE C0402
J 0
(-8175 5975);
DISPLAY 0.489362 (-8175 5975);
PAINT SKYBLUE (-8175 5975);
FORCEPROP 2 LAST CDS_LIB pure_quanta
J 0
(-8225 6075);
DISPLAY INVISIBLE (-8225 6075);
FORCEPROP 1 LAST PATH I44
J 0
(-8175 6225);
DISPLAY 0.978723 (-8175 6225);
PAINT WHITE (-8175 6225);
DISPLAY INVISIBLE (-8175 6225);
FORCEADD Q_INDUCTOR4P_14..1
(-6425 2200);
FORCEPROP 1 LAST LOCATION PL20
J 0
(-6700 2375);
DISPLAY 0.489362 (-6700 2375);
PAINT SKYBLUE (-6700 2375);
FORCEPROP 0 LAST $SEC 1
J 0
(-6375 2400);
DISPLAY 0.680851 (-6375 2400);
PAINT MONO (-6375 2400);
DISPLAY INVISIBLE (-6375 2400);
FORCEPROP 0 LAST CDS_SEC 1
J 0
(-6375 2400);
DISPLAY 1.021277 (-6375 2400);
DISPLAY INVISIBLE (-6375 2400);
FORCEPROP 0 LASTPIN (-6825 2325) $PN 1
J 2
(-6835 2335);
DISPLAY 0.489362 (-6835 2335);
PAINT MONO (-6835 2335);
FORCEPROP 0 LASTPIN (-6825 2075) $PN 2
J 2
(-6835 2085);
DISPLAY 0.489362 (-6835 2085);
PAINT MONO (-6835 2085);
FORCEPROP 0 LASTPIN (-6025 2075) $PN 3
J 0
(-6015 2085);
DISPLAY 0.489362 (-6015 2085);
PAINT MONO (-6015 2085);
FORCEPROP 0 LASTPIN (-6025 2325) $PN 4
J 0
(-6015 2335);
DISPLAY 0.489362 (-6015 2335);
PAINT MONO (-6015 2335);
FORCEPROP 1 LAST MATERIAL IND
J 0
(-6625 2375);
DISPLAY 0.489362 (-6625 2375);
PAINT SKYBLUE (-6625 2375);
FORCEPROP 2 LAST VALUE 150NH
J 0
(-6525 2375);
DISPLAY 0.489362 (-6525 2375);
PAINT SKYBLUE (-6525 2375);
FORCEPROP 1 LAST PART_NUMBER CV+15^0TZ04
J 0
(-6375 2375);
DISPLAY 0.489362 (-6375 2375);
PAINT SKYBLUE (-6375 2375);
FORCEPROP 2 LAST PART_TYPE SMLF
J 0
(-6500 1950);
DISPLAY 1.021277 (-6500 1950);
FORCEPROP 2 LAST CDS_LIB pure_quanta
J 0
(-6425 2200);
DISPLAY INVISIBLE (-6425 2200);
FORCEPROP 1 LAST NEEDS_NO_SIZE TRUE
J 0
(-6425 2200);
DISPLAY 0.468085 (-6425 2200);
PAINT GREEN (-6425 2200);
DISPLAY INVISIBLE (-6425 2200);
FORCEPROP 1 LAST PATH I46
J 0
(-6225 2355);
DISPLAY 0.723404 (-6225 2355);
PAINT GREEN (-6225 2355);
DISPLAY INVISIBLE (-6225 2355);
FORCEADD UNIVERSAL_GND..1
(-6875 2900);
FORCEPROP 3 LASTPIN (-6875 2950) SIG_NAME GND\g
J 0
(-6865 2960);
DISPLAY 0.659574 (-6865 2960);
PAINT MONO (-6865 2960);
DISPLAY INVISIBLE (-6865 2960);
FORCEPROP 2 LAST CDS_LIB pure_quanta_power
J 0
(-6875 2900);
PAINT MONO (-6875 2900);
DISPLAY INVISIBLE (-6875 2900);
FORCEPROP 1 LAST PATH I49
J 0
(-6800 2900);
DISPLAY 0.872340 (-6800 2900);
PAINT AQUA (-6800 2900);
DISPLAY INVISIBLE (-6800 2900);
FORCEPROP 1 LAST HDL_POWER GND
J 1
(-6850 2825);
DISPLAY 0.872340 (-6850 2825);
PAINT GREEN (-6850 2825);
DISPLAY INVISIBLE (-6850 2825);
FORCEADD OFFPAGE..5
(-11050 1825);
FORCEPROP 2 LAST $XR2 176 
J 0
(-11335 1861);
DISPLAY 0.638298 (-11335 1861);
PAINT MONO (-11335 1861);
FORCEPROP 2 LAST $XR1 182 
J 0
(-11335 1789);
DISPLAY 0.638298 (-11335 1789);
PAINT MONO (-11335 1789);
FORCEPROP 2 LAST $XR0 181 
J 0
(-11335 1825);
DISPLAY 0.638298 (-11335 1825);
PAINT MONO (-11335 1825);
FORCEPROP 2 LAST CDS_LIB standard
J 0
(-11050 1825);
DISPLAY INVISIBLE (-11050 1825);
FORCEPROP 1 LAST OFFPAGE TRUE
J 0
(-10725 1700);
DISPLAY 0.872340 (-10725 1700);
PAINT GREEN (-10725 1700);
DISPLAY INVISIBLE (-10725 1700);
FORCEPROP 1 LAST COMMENT_BODY TRUE
J 0
(-10950 1750);
DISPLAY 0.872340 (-10950 1750);
PAINT GREEN (-10950 1750);
DISPLAY INVISIBLE (-10950 1750);
FORCEPROP 2 LAST PATH I5
J 0
(-11325 2000);
DISPLAY 1.021277 (-11325 2000);
DISPLAY INVISIBLE (-11325 2000);
FORCEADD Q_CAP..1
(-7750 3275);
FORCEPROP 1 LAST LOCATION PC182_4
J 0
(-7700 3425);
DISPLAY 0.489362 (-7700 3425);
PAINT SKYBLUE (-7700 3425);
FORCEPROP 0 LAST $SEC 1
J 0
(-7700 3475);
DISPLAY 0.680851 (-7700 3475);
PAINT MONO (-7700 3475);
DISPLAY INVISIBLE (-7700 3475);
FORCEPROP 0 LAST CDS_SEC 1
J 0
(-7700 3475);
DISPLAY 1.021277 (-7700 3475);
DISPLAY INVISIBLE (-7700 3475);
FORCEPROP 1 LASTPIN (-7750 3375) $PN 1
J 0
(-7740 3355);
DISPLAY 0.489362 (-7740 3355);
PAINT MONO (-7740 3355);
FORCEPROP 1 LASTPIN (-7750 3175) $PN 2
J 0
(-7740 3155);
DISPLAY 0.489362 (-7740 3155);
PAINT MONO (-7740 3155);
FORCEPROP 1 LAST MATERIAL X6S
J 0
(-7700 3225);
DISPLAY 0.489362 (-7700 3225);
PAINT SKYBLUE (-7700 3225);
FORCEPROP 1 LAST TOLERANCE 10%
J 0
(-7700 3275);
DISPLAY 0.489362 (-7700 3275);
PAINT SKYBLUE (-7700 3275);
FORCEPROP 1 LAST VALUE 10UF
J 0
(-7700 3375);
DISPLAY 0.489362 (-7700 3375);
PAINT SKYBLUE (-7700 3375);
FORCEPROP 1 LAST PART_NUMBER CH6104KEA00
J 0
(-7700 3125);
DISPLAY 0.489362 (-7700 3125);
PAINT SKYBLUE (-7700 3125);
FORCEPROP 1 LAST VOLTAGE 25V
J 0
(-7700 3325);
DISPLAY 0.489362 (-7700 3325);
PAINT SKYBLUE (-7700 3325);
FORCEPROP 1 LAST PACK_TYPE C0805
J 0
(-7700 3175);
DISPLAY 0.489362 (-7700 3175);
PAINT SKYBLUE (-7700 3175);
FORCEPROP 2 LAST CDS_LIB pure_quanta
J 0
(-7750 3275);
DISPLAY INVISIBLE (-7750 3275);
FORCEPROP 1 LAST PATH I51
J 0
(-7700 3425);
DISPLAY 0.978723 (-7700 3425);
PAINT WHITE (-7700 3425);
DISPLAY INVISIBLE (-7700 3425);
FORCEADD Q_CAP..1
(-7350 3275);
FORCEPROP 1 LAST LOCATION PC185_4
J 0
(-7300 3425);
DISPLAY 0.489362 (-7300 3425);
PAINT SKYBLUE (-7300 3425);
FORCEPROP 0 LAST $SEC 1
J 0
(-7300 3475);
DISPLAY 0.680851 (-7300 3475);
PAINT MONO (-7300 3475);
DISPLAY INVISIBLE (-7300 3475);
FORCEPROP 0 LAST CDS_SEC 1
J 0
(-7300 3475);
DISPLAY 1.021277 (-7300 3475);
DISPLAY INVISIBLE (-7300 3475);
FORCEPROP 1 LASTPIN (-7350 3375) $PN 1
J 0
(-7340 3355);
DISPLAY 0.489362 (-7340 3355);
PAINT MONO (-7340 3355);
FORCEPROP 1 LASTPIN (-7350 3175) $PN 2
J 0
(-7340 3155);
DISPLAY 0.489362 (-7340 3155);
PAINT MONO (-7340 3155);
FORCEPROP 1 LAST MATERIAL X6S
J 0
(-7300 3225);
DISPLAY 0.489362 (-7300 3225);
PAINT SKYBLUE (-7300 3225);
FORCEPROP 1 LAST TOLERANCE 10%
J 0
(-7300 3275);
DISPLAY 0.489362 (-7300 3275);
PAINT SKYBLUE (-7300 3275);
FORCEPROP 1 LAST VALUE 10UF
J 0
(-7300 3375);
DISPLAY 0.489362 (-7300 3375);
PAINT SKYBLUE (-7300 3375);
FORCEPROP 1 LAST PART_NUMBER CH6104KEA00
J 0
(-7300 3125);
DISPLAY 0.489362 (-7300 3125);
PAINT SKYBLUE (-7300 3125);
FORCEPROP 1 LAST PACK_TYPE C0805
J 0
(-7300 3175);
DISPLAY 0.489362 (-7300 3175);
PAINT SKYBLUE (-7300 3175);
FORCEPROP 1 LAST VOLTAGE 25V
J 0
(-7300 3325);
DISPLAY 0.489362 (-7300 3325);
PAINT SKYBLUE (-7300 3325);
FORCEPROP 2 LAST CDS_LIB pure_quanta
J 0
(-7350 3275);
DISPLAY INVISIBLE (-7350 3275);
FORCEPROP 1 LAST PATH I52
J 0
(-7300 3425);
DISPLAY 0.978723 (-7300 3425);
PAINT WHITE (-7300 3425);
DISPLAY INVISIBLE (-7300 3425);
FORCEADD Q_CAP..1
(-6875 3275);
FORCEPROP 1 LAST LOCATION PC188_4
J 0
(-6825 3375);
DISPLAY 0.489362 (-6825 3375);
PAINT SKYBLUE (-6825 3375);
FORCEPROP 0 LAST $SEC 1
J 0
(-6825 3425);
DISPLAY 0.680851 (-6825 3425);
PAINT MONO (-6825 3425);
DISPLAY INVISIBLE (-6825 3425);
FORCEPROP 0 LAST CDS_SEC 1
J 0
(-6825 3425);
DISPLAY 1.021277 (-6825 3425);
DISPLAY INVISIBLE (-6825 3425);
FORCEPROP 1 LASTPIN (-6875 3375) $PN 1
J 0
(-6865 3355);
DISPLAY 0.489362 (-6865 3355);
PAINT MONO (-6865 3355);
FORCEPROP 1 LASTPIN (-6875 3175) $PN 2
J 0
(-6865 3155);
DISPLAY 0.489362 (-6865 3155);
PAINT MONO (-6865 3155);
FORCEPROP 1 LAST MATERIAL X6S
J 0
(-6825 3175);
DISPLAY 0.489362 (-6825 3175);
PAINT SKYBLUE (-6825 3175);
FORCEPROP 1 LAST TOLERANCE 10%
J 0
(-6825 3225);
DISPLAY 0.489362 (-6825 3225);
PAINT SKYBLUE (-6825 3225);
FORCEPROP 1 LAST VALUE 10UF
J 0
(-6825 3325);
DISPLAY 0.489362 (-6825 3325);
PAINT SKYBLUE (-6825 3325);
FORCEPROP 1 LAST PART_NUMBER CH6104KEA00
J 0
(-6825 3125);
DISPLAY 0.489362 (-6825 3125);
PAINT SKYBLUE (-6825 3125);
FORCEPROP 1 LAST VOLTAGE 25V
J 0
(-6825 3275);
DISPLAY 0.489362 (-6825 3275);
PAINT SKYBLUE (-6825 3275);
FORCEPROP 1 LAST PACK_TYPE C0805
J 0
(-6825 3075);
DISPLAY 0.489362 (-6825 3075);
PAINT SKYBLUE (-6825 3075);
FORCEPROP 2 LAST CDS_LIB pure_quanta
J 0
(-6875 3275);
DISPLAY INVISIBLE (-6875 3275);
FORCEPROP 1 LAST PATH I55
J 0
(-6825 3425);
DISPLAY 0.978723 (-6825 3425);
PAINT WHITE (-6825 3425);
DISPLAY INVISIBLE (-6825 3425);
FORCEADD Q_RES..1
(-6850 4000);
FORCEPROP 1 LAST LOCATION PR111
J 0
(-6900 4025);
DISPLAY 0.489362 (-6900 4025);
PAINT SKYBLUE (-6900 4025);
FORCEPROP 0 LAST $SEC 1
J 0
(-6975 4175);
DISPLAY 0.680851 (-6975 4175);
PAINT MONO (-6975 4175);
DISPLAY INVISIBLE (-6975 4175);
FORCEPROP 0 LAST CDS_SEC 1
J 0
(-6975 4175);
DISPLAY 1.021277 (-6975 4175);
DISPLAY INVISIBLE (-6975 4175);
FORCEPROP 1 LASTPIN (-6950 4000) $PN 1
J 0
(-6938 4012);
DISPLAY 0.787234 (-6938 4012);
PAINT MONO (-6938 4012);
DISPLAY INVISIBLE (-6938 4012);
FORCEPROP 1 LASTPIN (-6750 4000) $PN 2
J 0
(-6788 4012);
DISPLAY 0.787234 (-6788 4012);
PAINT MONO (-6788 4012);
DISPLAY INVISIBLE (-6788 4012);
FORCEPROP 1 LAST WATTAGE 1/16W
J 2
(-6625 4075);
DISPLAY 0.489362 (-6625 4075);
PAINT SKYBLUE (-6625 4075);
FORCEPROP 1 LAST MATERIAL CHIP
J 0
(-6725 4025);
DISPLAY 0.489362 (-6725 4025);
PAINT SKYBLUE (-6725 4025);
FORCEPROP 1 LAST TOLERANCE 5%
J 0
(-7025 4025);
DISPLAY 0.489362 (-7025 4025);
PAINT SKYBLUE (-7025 4025);
FORCEPROP 1 LAST VALUE 0
J 2
(-7050 4025);
DISPLAY 0.489362 (-7050 4025);
PAINT SKYBLUE (-7050 4025);
FORCEPROP 1 LAST PART_NUMBER CS00002JB38
J 0
(-7150 3950);
DISPLAY 0.489362 (-7150 3950);
PAINT SKYBLUE (-7150 3950);
FORCEPROP 1 LAST PACK_TYPE 0402LF
J 0
(-6775 3950);
DISPLAY 0.489362 (-6775 3950);
PAINT SKYBLUE (-6775 3950);
FORCEPROP 2 LAST CDS_LIB pure_quanta
J 0
(-6850 4000);
DISPLAY INVISIBLE (-6850 4000);
FORCEPROP 1 LAST PATH I57
J 0
(-6900 4150);
DISPLAY 0.978723 (-6900 4150);
PAINT WHITE (-6900 4150);
DISPLAY INVISIBLE (-6900 4150);
FORCEADD Q_CAP..1
(-4350 2125);
FORCEPROP 1 LAST LOCATION PC189_4
J 0
(-4300 2250);
DISPLAY 0.489362 (-4300 2250);
PAINT SKYBLUE (-4300 2250);
FORCEPROP 0 LAST $SEC 1
J 0
(-4300 2300);
DISPLAY 0.680851 (-4300 2300);
PAINT MONO (-4300 2300);
DISPLAY INVISIBLE (-4300 2300);
FORCEPROP 0 LAST CDS_SEC 1
J 0
(-4300 2300);
DISPLAY 1.021277 (-4300 2300);
DISPLAY INVISIBLE (-4300 2300);
FORCEPROP 1 LASTPIN (-4350 2225) $PN 1
J 0
(-4340 2205);
DISPLAY 0.489362 (-4340 2205);
PAINT MONO (-4340 2205);
FORCEPROP 1 LASTPIN (-4350 2025) $PN 2
J 0
(-4340 2005);
DISPLAY 0.489362 (-4340 2005);
PAINT MONO (-4340 2005);
FORCEPROP 1 LAST MATERIAL X6S
J 0
(-4300 2050);
DISPLAY 0.489362 (-4300 2050);
PAINT SKYBLUE (-4300 2050);
FORCEPROP 1 LAST TOLERANCE 20%
J 0
(-4300 2100);
DISPLAY 0.489362 (-4300 2100);
PAINT SKYBLUE (-4300 2100);
FORCEPROP 1 LAST VALUE 22UF
J 0
(-4300 2200);
DISPLAY 0.489362 (-4300 2200);
PAINT SKYBLUE (-4300 2200);
FORCEPROP 1 LAST PART_NUMBER TMP_QCH622KMEA01
J 0
(-4300 1950);
DISPLAY 0.489362 (-4300 1950);
PAINT SKYBLUE (-4300 1950);
FORCEPROP 1 LAST VOLTAGE 4V
J 0
(-4300 2150);
DISPLAY 0.489362 (-4300 2150);
PAINT SKYBLUE (-4300 2150);
FORCEPROP 1 LAST PACK_TYPE 0805
J 0
(-4300 2000);
DISPLAY 0.489362 (-4300 2000);
PAINT SKYBLUE (-4300 2000);
FORCEPROP 2 LAST CDS_LIB pure_quanta
J 0
(-4350 2125);
DISPLAY INVISIBLE (-4350 2125);
FORCEPROP 1 LAST PATH I59
J 0
(-4300 2275);
DISPLAY 0.978723 (-4300 2275);
PAINT WHITE (-4300 2275);
DISPLAY INVISIBLE (-4300 2275);
FORCEADD OFFPAGE..1
(-11050 2225);
FORCEPROP 2 LAST $XR5 182 
J 0
(-11902 2225);
DISPLAY 0.638298 (-11902 2225);
PAINT MONO (-11902 2225);
FORCEPROP 2 LAST $XR4 181 
J 0
(-11782 2225);
DISPLAY 0.638298 (-11782 2225);
PAINT MONO (-11782 2225);
FORCEPROP 2 LAST $XR3 179 
J 0
(-11662 2225);
DISPLAY 0.638298 (-11662 2225);
PAINT MONO (-11662 2225);
FORCEPROP 2 LAST $XR2 178 
J 0
(-11542 2225);
DISPLAY 0.638298 (-11542 2225);
PAINT MONO (-11542 2225);
FORCEPROP 2 LAST $XR1 177 
J 0
(-11422 2225);
DISPLAY 0.638298 (-11422 2225);
PAINT MONO (-11422 2225);
FORCEPROP 2 LAST $XR0 176 
J 0
(-11302 2225);
DISPLAY 0.638298 (-11302 2225);
PAINT MONO (-11302 2225);
FORCEPROP 2 LAST CDS_LIB standard
J 0
(-11050 2225);
DISPLAY INVISIBLE (-11050 2225);
FORCEPROP 1 LAST OFFPAGE TRUE
J 0
(-10725 2100);
DISPLAY 0.872340 (-10725 2100);
PAINT GREEN (-10725 2100);
DISPLAY INVISIBLE (-10725 2100);
FORCEPROP 1 LAST COMMENT_BODY TRUE
J 0
(-10925 2125);
DISPLAY 0.872340 (-10925 2125);
PAINT GREEN (-10925 2125);
DISPLAY INVISIBLE (-10925 2125);
FORCEPROP 2 LAST PATH I6
J 0
(-11300 2275);
DISPLAY 1.021277 (-11300 2275);
DISPLAY INVISIBLE (-11300 2275);
FORCEADD OFFPAGE..3
(-5175 4875);
FORCEPROP 2 LAST $XR0 181 
J 0
(-4961 4875);
DISPLAY 0.638298 (-4961 4875);
PAINT MONO (-4961 4875);
FORCEPROP 2 LAST CDS_LIB standard
J 0
(-5175 4875);
DISPLAY INVISIBLE (-5175 4875);
FORCEPROP 1 LAST OFFPAGE TRUE
J 0
(-4850 4750);
DISPLAY 0.872340 (-4850 4750);
PAINT GREEN (-4850 4750);
DISPLAY INVISIBLE (-4850 4750);
FORCEPROP 1 LAST COMMENT_BODY TRUE
J 0
(-5225 4775);
DISPLAY 0.872340 (-5225 4775);
PAINT GREEN (-5225 4775);
DISPLAY INVISIBLE (-5225 4775);
FORCEPROP 2 LAST PATH I61
J 0
(-4975 4950);
DISPLAY 1.021277 (-4975 4950);
DISPLAY INVISIBLE (-4975 4950);
FORCEADD Q_CAP..1
(-4300 4925);
FORCEPROP 1 LAST LOCATION PC190_3
J 0
(-4250 5050);
DISPLAY 0.489362 (-4250 5050);
PAINT SKYBLUE (-4250 5050);
FORCEPROP 0 LAST $SEC 1
J 0
(-4250 5100);
DISPLAY 0.680851 (-4250 5100);
PAINT MONO (-4250 5100);
DISPLAY INVISIBLE (-4250 5100);
FORCEPROP 0 LAST CDS_SEC 1
J 0
(-4250 5100);
DISPLAY 1.021277 (-4250 5100);
DISPLAY INVISIBLE (-4250 5100);
FORCEPROP 1 LASTPIN (-4300 5025) $PN 1
J 0
(-4290 5005);
DISPLAY 0.489362 (-4290 5005);
PAINT MONO (-4290 5005);
FORCEPROP 1 LASTPIN (-4300 4825) $PN 2
J 0
(-4290 4805);
DISPLAY 0.489362 (-4290 4805);
PAINT MONO (-4290 4805);
FORCEPROP 1 LAST MATERIAL X6S
J 0
(-4250 4850);
DISPLAY 0.489362 (-4250 4850);
PAINT SKYBLUE (-4250 4850);
FORCEPROP 1 LAST TOLERANCE 20%
J 0
(-4250 4900);
DISPLAY 0.489362 (-4250 4900);
PAINT SKYBLUE (-4250 4900);
FORCEPROP 1 LAST VALUE 22UF
J 0
(-4250 5000);
DISPLAY 0.489362 (-4250 5000);
PAINT SKYBLUE (-4250 5000);
FORCEPROP 1 LAST PART_NUMBER TMP_QCH622KMEA01
J 0
(-4250 4750);
DISPLAY 0.489362 (-4250 4750);
PAINT SKYBLUE (-4250 4750);
FORCEPROP 1 LAST VOLTAGE 4V
J 0
(-4250 4950);
DISPLAY 0.489362 (-4250 4950);
PAINT SKYBLUE (-4250 4950);
FORCEPROP 1 LAST PACK_TYPE 0805
J 0
(-4250 4800);
DISPLAY 0.489362 (-4250 4800);
PAINT SKYBLUE (-4250 4800);
FORCEPROP 2 LAST CDS_LIB pure_quanta
J 0
(-4300 4925);
DISPLAY INVISIBLE (-4300 4925);
FORCEPROP 1 LAST PATH I65
J 0
(-4250 5075);
DISPLAY 0.978723 (-4250 5075);
PAINT WHITE (-4250 5075);
DISPLAY INVISIBLE (-4250 5075);
FORCEADD Q_CAP..1
(-7825 6075);
FORCEPROP 1 LAST LOCATION PC181_3
J 0
(-7775 6225);
DISPLAY 0.489362 (-7775 6225);
PAINT SKYBLUE (-7775 6225);
FORCEPROP 0 LAST $SEC 1
J 0
(-7775 6275);
DISPLAY 0.680851 (-7775 6275);
PAINT MONO (-7775 6275);
DISPLAY INVISIBLE (-7775 6275);
FORCEPROP 0 LAST CDS_SEC 1
J 0
(-7775 6275);
DISPLAY 1.021277 (-7775 6275);
DISPLAY INVISIBLE (-7775 6275);
FORCEPROP 1 LASTPIN (-7825 6175) $PN 1
J 0
(-7815 6155);
DISPLAY 0.489362 (-7815 6155);
PAINT MONO (-7815 6155);
FORCEPROP 1 LASTPIN (-7825 5975) $PN 2
J 0
(-7815 5955);
DISPLAY 0.489362 (-7815 5955);
PAINT MONO (-7815 5955);
FORCEPROP 1 LAST MATERIAL X6S
J 0
(-7775 6025);
DISPLAY 0.489362 (-7775 6025);
PAINT SKYBLUE (-7775 6025);
FORCEPROP 1 LAST TOLERANCE 10%
J 0
(-7775 6075);
DISPLAY 0.489362 (-7775 6075);
PAINT SKYBLUE (-7775 6075);
FORCEPROP 1 LAST VALUE 10UF
J 0
(-7775 6175);
DISPLAY 0.489362 (-7775 6175);
PAINT SKYBLUE (-7775 6175);
FORCEPROP 1 LAST VOLTAGE 25V
J 0
(-7775 6125);
DISPLAY 0.489362 (-7775 6125);
PAINT SKYBLUE (-7775 6125);
FORCEPROP 1 LAST PACK_TYPE C0805
J 0
(-7775 5975);
DISPLAY 0.489362 (-7775 5975);
PAINT SKYBLUE (-7775 5975);
FORCEPROP 1 LAST PART_NUMBER CH6104KEA00
J 0
(-7775 5925);
DISPLAY 0.489362 (-7775 5925);
PAINT SKYBLUE (-7775 5925);
FORCEPROP 2 LAST CDS_LIB pure_quanta
J 0
(-7825 6075);
DISPLAY INVISIBLE (-7825 6075);
FORCEPROP 1 LAST PATH I67
J 0
(-7775 6225);
DISPLAY 0.978723 (-7775 6225);
PAINT WHITE (-7775 6225);
DISPLAY INVISIBLE (-7775 6225);
FORCEADD Q_CAP..1
(-7425 6075);
FORCEPROP 1 LAST LOCATION PC184_3
J 0
(-7375 6225);
DISPLAY 0.489362 (-7375 6225);
PAINT SKYBLUE (-7375 6225);
FORCEPROP 0 LAST $SEC 1
J 0
(-7375 6275);
DISPLAY 0.680851 (-7375 6275);
PAINT MONO (-7375 6275);
DISPLAY INVISIBLE (-7375 6275);
FORCEPROP 0 LAST CDS_SEC 1
J 0
(-7375 6275);
DISPLAY 1.021277 (-7375 6275);
DISPLAY INVISIBLE (-7375 6275);
FORCEPROP 1 LASTPIN (-7425 6175) $PN 1
J 0
(-7415 6155);
DISPLAY 0.489362 (-7415 6155);
PAINT MONO (-7415 6155);
FORCEPROP 1 LASTPIN (-7425 5975) $PN 2
J 0
(-7415 5955);
DISPLAY 0.489362 (-7415 5955);
PAINT MONO (-7415 5955);
FORCEPROP 1 LAST MATERIAL X6S
J 0
(-7375 6025);
DISPLAY 0.489362 (-7375 6025);
PAINT SKYBLUE (-7375 6025);
FORCEPROP 1 LAST TOLERANCE 10%
J 0
(-7375 6075);
DISPLAY 0.489362 (-7375 6075);
PAINT SKYBLUE (-7375 6075);
FORCEPROP 1 LAST VALUE 10UF
J 0
(-7375 6175);
DISPLAY 0.489362 (-7375 6175);
PAINT SKYBLUE (-7375 6175);
FORCEPROP 1 LAST VOLTAGE 25V
J 0
(-7375 6125);
DISPLAY 0.489362 (-7375 6125);
PAINT SKYBLUE (-7375 6125);
FORCEPROP 1 LAST PACK_TYPE C0805
J 0
(-7375 5975);
DISPLAY 0.489362 (-7375 5975);
PAINT SKYBLUE (-7375 5975);
FORCEPROP 1 LAST PART_NUMBER CH6104KEA00
J 0
(-7375 5925);
DISPLAY 0.489362 (-7375 5925);
PAINT SKYBLUE (-7375 5925);
FORCEPROP 2 LAST CDS_LIB pure_quanta
J 0
(-7425 6075);
DISPLAY INVISIBLE (-7425 6075);
FORCEPROP 1 LAST PATH I68
J 0
(-7375 6225);
DISPLAY 0.978723 (-7375 6225);
PAINT WHITE (-7375 6225);
DISPLAY INVISIBLE (-7375 6225);
FORCEADD Q_CAP..1
(-7200 5350);
FORCEPROP 1 LAST LOCATION PC186
J 0
(-7150 5450);
DISPLAY 0.489362 (-7150 5450);
PAINT SKYBLUE (-7150 5450);
FORCEPROP 0 LAST $SEC 1
J 0
(-7150 5500);
DISPLAY 0.680851 (-7150 5500);
PAINT MONO (-7150 5500);
DISPLAY INVISIBLE (-7150 5500);
FORCEPROP 0 LAST CDS_SEC 1
J 0
(-7150 5500);
DISPLAY 1.021277 (-7150 5500);
DISPLAY INVISIBLE (-7150 5500);
FORCEPROP 1 LASTPIN (-7200 5450) $PN 1
J 0
(-7190 5430);
DISPLAY 0.489362 (-7190 5430);
PAINT MONO (-7190 5430);
FORCEPROP 1 LASTPIN (-7200 5250) $PN 2
J 0
(-7190 5230);
DISPLAY 0.489362 (-7190 5230);
PAINT MONO (-7190 5230);
FORCEPROP 1 LAST MATERIAL X7R
J 0
(-7150 5250);
DISPLAY 0.489362 (-7150 5250);
PAINT SKYBLUE (-7150 5250);
FORCEPROP 1 LAST TOLERANCE 10%
J 0
(-7150 5300);
DISPLAY 0.489362 (-7150 5300);
PAINT SKYBLUE (-7150 5300);
FORCEPROP 1 LAST VALUE 0.22UF
J 0
(-7150 5400);
DISPLAY 0.489362 (-7150 5400);
PAINT SKYBLUE (-7150 5400);
FORCEPROP 1 LAST PART_NUMBER CH4223K1B00
J 0
(-7150 5200);
DISPLAY 0.489362 (-7150 5200);
PAINT SKYBLUE (-7150 5200);
FORCEPROP 1 LAST VOLTAGE 16V
J 0
(-7150 5350);
DISPLAY 0.489362 (-7150 5350);
PAINT SKYBLUE (-7150 5350);
FORCEPROP 1 LAST PACK_TYPE 0402
J 0
(-7150 5150);
DISPLAY 0.489362 (-7150 5150);
PAINT SKYBLUE (-7150 5150);
FORCEPROP 2 LAST CDS_LIB pure_quanta
J 0
(-7200 5350);
PAINT MONO (-7200 5350);
DISPLAY INVISIBLE (-7200 5350);
FORCEPROP 1 LAST PATH I69
J 0
(-7150 5500);
DISPLAY 0.978723 (-7150 5500);
PAINT WHITE (-7150 5500);
DISPLAY INVISIBLE (-7150 5500);
FORCEADD OFFPAGE..5
(-11050 2325);
FORCEPROP 2 LAST $XR0 176 
J 0
(-11335 2325);
DISPLAY 0.638298 (-11335 2325);
PAINT MONO (-11335 2325);
FORCEPROP 2 LAST CDS_LIB standard
J 0
(-11050 2325);
DISPLAY INVISIBLE (-11050 2325);
FORCEPROP 1 LAST OFFPAGE TRUE
J 0
(-10725 2200);
DISPLAY 0.872340 (-10725 2200);
PAINT GREEN (-10725 2200);
DISPLAY INVISIBLE (-10725 2200);
FORCEPROP 1 LAST COMMENT_BODY TRUE
J 0
(-10950 2250);
DISPLAY 0.872340 (-10950 2250);
PAINT GREEN (-10950 2250);
DISPLAY INVISIBLE (-10950 2250);
FORCEPROP 2 LAST PATH I7
J 0
(-11325 2375);
DISPLAY 1.021277 (-11325 2375);
DISPLAY INVISIBLE (-11325 2375);
FORCEADD UNIVERSAL_GND..1
(-7000 5700);
FORCEPROP 3 LASTPIN (-7000 5750) SIG_NAME GND\g
J 0
(-6990 5760);
DISPLAY 0.659574 (-6990 5760);
PAINT MONO (-6990 5760);
DISPLAY INVISIBLE (-6990 5760);
FORCEPROP 2 LAST CDS_LIB pure_quanta_power
J 0
(-7000 5700);
PAINT MONO (-7000 5700);
DISPLAY INVISIBLE (-7000 5700);
FORCEPROP 1 LAST PATH I70
J 0
(-6925 5700);
DISPLAY 0.872340 (-6925 5700);
PAINT AQUA (-6925 5700);
DISPLAY INVISIBLE (-6925 5700);
FORCEPROP 1 LAST HDL_POWER GND
J 1
(-6975 5625);
DISPLAY 0.872340 (-6975 5625);
PAINT GREEN (-6975 5625);
DISPLAY INVISIBLE (-6975 5625);
FORCEADD Q_CAP..1
(-7000 6100);
FORCEPROP 1 LAST LOCATION PC187_3
J 0
(-6950 6200);
DISPLAY 0.489362 (-6950 6200);
PAINT SKYBLUE (-6950 6200);
FORCEPROP 0 LAST $SEC 1
J 0
(-6950 6250);
DISPLAY 0.680851 (-6950 6250);
PAINT MONO (-6950 6250);
DISPLAY INVISIBLE (-6950 6250);
FORCEPROP 0 LAST CDS_SEC 1
J 0
(-6950 6250);
DISPLAY 1.021277 (-6950 6250);
DISPLAY INVISIBLE (-6950 6250);
FORCEPROP 1 LASTPIN (-7000 6200) $PN 1
J 0
(-6990 6180);
DISPLAY 0.489362 (-6990 6180);
PAINT MONO (-6990 6180);
FORCEPROP 1 LASTPIN (-7000 6000) $PN 2
J 0
(-6990 5980);
DISPLAY 0.489362 (-6990 5980);
PAINT MONO (-6990 5980);
FORCEPROP 1 LAST MATERIAL X6S
J 0
(-6950 6000);
DISPLAY 0.489362 (-6950 6000);
PAINT SKYBLUE (-6950 6000);
FORCEPROP 1 LAST TOLERANCE 10%
J 0
(-6950 6050);
DISPLAY 0.489362 (-6950 6050);
PAINT SKYBLUE (-6950 6050);
FORCEPROP 1 LAST VALUE 10UF
J 0
(-6950 6150);
DISPLAY 0.489362 (-6950 6150);
PAINT SKYBLUE (-6950 6150);
FORCEPROP 1 LAST PART_NUMBER CH6104KEA00
J 0
(-6950 5950);
DISPLAY 0.489362 (-6950 5950);
PAINT SKYBLUE (-6950 5950);
FORCEPROP 1 LAST VOLTAGE 25V
J 0
(-6950 6100);
DISPLAY 0.489362 (-6950 6100);
PAINT SKYBLUE (-6950 6100);
FORCEPROP 1 LAST PACK_TYPE C0805
J 0
(-6950 5900);
DISPLAY 0.489362 (-6950 5900);
PAINT SKYBLUE (-6950 5900);
FORCEPROP 2 LAST CDS_LIB pure_quanta
J 0
(-7000 6100);
DISPLAY INVISIBLE (-7000 6100);
FORCEPROP 1 LAST PATH I71
J 0
(-6950 6250);
DISPLAY 0.978723 (-6950 6250);
PAINT WHITE (-6950 6250);
DISPLAY INVISIBLE (-6950 6250);
FORCEADD VCC_CORE..1
(-7000 6450);
FORCEPROP 3 LASTPIN (-7000 6400) SIG_NAME SW_P12V_STBY_PVDDIO_P0_FLT\g
J 0
(-6990 6410);
DISPLAY 0.659574 (-6990 6410);
PAINT MONO (-6990 6410);
DISPLAY INVISIBLE (-6990 6410);
FORCEPROP 1 LAST HDL_POWER SW_P12V_STBY_PVDDIO_P0_FLT
J 1
(-7000 6500);
DISPLAY 0.489362 (-7000 6500);
PAINT GREEN (-7000 6500);
FORCEPROP 2 LAST CDS_LIB pure_quanta_power
J 0
(-7000 6450);
DISPLAY INVISIBLE (-7000 6450);
FORCEPROP 1 LAST PATH I72
J 0
(-6950 6475);
DISPLAY 0.872340 (-6950 6475);
PAINT AQUA (-6950 6475);
DISPLAY INVISIBLE (-6950 6475);
FORCEADD UNIVERSAL_GND..1
(-3925 1775);
FORCEPROP 3 LASTPIN (-3925 1825) SIG_NAME GND\g
J 0
(-3915 1835);
DISPLAY 0.659574 (-3915 1835);
PAINT MONO (-3915 1835);
DISPLAY INVISIBLE (-3915 1835);
FORCEPROP 2 LAST CDS_LIB pure_quanta_power
J 0
(-3925 1775);
PAINT MONO (-3925 1775);
DISPLAY INVISIBLE (-3925 1775);
FORCEPROP 1 LAST PATH I77
J 0
(-3850 1775);
DISPLAY 0.872340 (-3850 1775);
PAINT AQUA (-3850 1775);
DISPLAY INVISIBLE (-3850 1775);
FORCEPROP 1 LAST HDL_POWER GND
J 1
(-3900 1700);
DISPLAY 0.872340 (-3900 1700);
PAINT GREEN (-3900 1700);
DISPLAY INVISIBLE (-3900 1700);
FORCEADD Q_CAP..1
(-3925 2125);
FORCEPROP 1 LAST LOCATION PC191_4
J 0
(-3875 2250);
DISPLAY 0.489362 (-3875 2250);
PAINT SKYBLUE (-3875 2250);
FORCEPROP 0 LAST $SEC 1
J 0
(-3875 2300);
DISPLAY 0.680851 (-3875 2300);
PAINT MONO (-3875 2300);
DISPLAY INVISIBLE (-3875 2300);
FORCEPROP 0 LAST CDS_SEC 1
J 0
(-3875 2300);
DISPLAY 1.021277 (-3875 2300);
DISPLAY INVISIBLE (-3875 2300);
FORCEPROP 1 LASTPIN (-3925 2225) $PN 1
J 0
(-3915 2205);
DISPLAY 0.489362 (-3915 2205);
PAINT MONO (-3915 2205);
FORCEPROP 1 LASTPIN (-3925 2025) $PN 2
J 0
(-3915 2005);
DISPLAY 0.489362 (-3915 2005);
PAINT MONO (-3915 2005);
FORCEPROP 1 LAST MATERIAL X6S
J 0
(-3875 2050);
DISPLAY 0.489362 (-3875 2050);
PAINT SKYBLUE (-3875 2050);
FORCEPROP 1 LAST TOLERANCE 20%
J 0
(-3875 2100);
DISPLAY 0.489362 (-3875 2100);
PAINT SKYBLUE (-3875 2100);
FORCEPROP 1 LAST VALUE 22UF
J 0
(-3875 2200);
DISPLAY 0.489362 (-3875 2200);
PAINT SKYBLUE (-3875 2200);
FORCEPROP 1 LAST PART_NUMBER TMP_QCH622KMEA01
J 0
(-3875 1950);
DISPLAY 0.489362 (-3875 1950);
PAINT SKYBLUE (-3875 1950);
FORCEPROP 1 LAST VOLTAGE 4V
J 0
(-3875 2150);
DISPLAY 0.489362 (-3875 2150);
PAINT SKYBLUE (-3875 2150);
FORCEPROP 1 LAST PACK_TYPE 0805
J 0
(-3875 2000);
DISPLAY 0.489362 (-3875 2000);
PAINT SKYBLUE (-3875 2000);
FORCEPROP 2 LAST CDS_LIB pure_quanta
J 0
(-3925 2125);
DISPLAY INVISIBLE (-3925 2125);
FORCEPROP 1 LAST PATH I78
J 0
(-3875 2275);
DISPLAY 0.978723 (-3875 2275);
PAINT WHITE (-3875 2275);
DISPLAY INVISIBLE (-3875 2275);
FORCEADD VCC_CORE..1
(-3925 2450);
FORCEPROP 3 LASTPIN (-3925 2400) SIG_NAME PVDDIO_P0\g
J 0
(-3915 2410);
DISPLAY 0.659574 (-3915 2410);
PAINT MONO (-3915 2410);
DISPLAY INVISIBLE (-3915 2410);
FORCEPROP 1 LAST HDL_POWER PVDDIO_P0
J 1
(-3925 2500);
DISPLAY 0.489362 (-3925 2500);
PAINT GREEN (-3925 2500);
FORCEPROP 2 LAST CDS_LIB pure_quanta_power
J 0
(-3925 2450);
DISPLAY INVISIBLE (-3925 2450);
FORCEPROP 1 LAST PATH I79
J 0
(-3875 2475);
DISPLAY 0.872340 (-3875 2475);
PAINT AQUA (-3875 2475);
DISPLAY INVISIBLE (-3875 2475);
FORCEADD Q_CAP..1
(-12050 1950);
FORCEPROP 1 LAST LOCATION PC176_10
J 0
(-12000 2050);
DISPLAY 0.489362 (-12000 2050);
PAINT SKYBLUE (-12000 2050);
FORCEPROP 0 LAST $SEC 1
J 0
(-12000 2075);
DISPLAY 0.680851 (-12000 2075);
PAINT MONO (-12000 2075);
DISPLAY INVISIBLE (-12000 2075);
FORCEPROP 2 LAST CDS_SEC 1
J 0
(-12050 2200);
DISPLAY 1.021277 (-12050 2200);
DISPLAY INVISIBLE (-12050 2200);
FORCEPROP 1 LASTPIN (-12050 2050) $PN 1
J 0
(-12040 2030);
DISPLAY 0.489362 (-12040 2030);
PAINT MONO (-12040 2030);
FORCEPROP 1 LASTPIN (-12050 1850) $PN 2
J 0
(-12040 1830);
DISPLAY 0.489362 (-12040 1830);
PAINT MONO (-12040 1830);
FORCEPROP 1 LAST MATERIAL X7R
J 0
(-12000 1850);
DISPLAY 0.489362 (-12000 1850);
PAINT SKYBLUE (-12000 1850);
FORCEPROP 1 LAST TOLERANCE 10%
J 0
(-12000 1900);
DISPLAY 0.489362 (-12000 1900);
PAINT SKYBLUE (-12000 1900);
FORCEPROP 1 LAST VALUE 0.1UF
J 0
(-12000 2000);
DISPLAY 0.489362 (-12000 2000);
PAINT SKYBLUE (-12000 2000);
FORCEPROP 1 LAST PART_NUMBER CH4104K1B00
J 0
(-12000 1800);
DISPLAY 0.489362 (-12000 1800);
PAINT SKYBLUE (-12000 1800);
FORCEPROP 1 LAST VOLTAGE 25V
J 0
(-12000 1950);
DISPLAY 0.489362 (-12000 1950);
PAINT SKYBLUE (-12000 1950);
FORCEPROP 1 LAST PACK_TYPE 0402
J 0
(-12000 1750);
DISPLAY 0.489362 (-12000 1750);
PAINT SKYBLUE (-12000 1750);
FORCEPROP 2 LAST CDS_LIB pure_quanta
J 0
(-12050 1950);
PAINT MONO (-12050 1950);
DISPLAY INVISIBLE (-12050 1950);
FORCEPROP 1 LAST PATH I8
J 0
(-12000 2100);
DISPLAY 0.978723 (-12000 2100);
PAINT WHITE (-12000 2100);
DISPLAY INVISIBLE (-12000 2100);
FORCEADD Q_CAP..1
(-3875 4925);
FORCEPROP 1 LAST LOCATION PC192_3
J 0
(-3825 5050);
DISPLAY 0.489362 (-3825 5050);
PAINT SKYBLUE (-3825 5050);
FORCEPROP 0 LAST $SEC 1
J 0
(-3825 5100);
DISPLAY 0.680851 (-3825 5100);
PAINT MONO (-3825 5100);
DISPLAY INVISIBLE (-3825 5100);
FORCEPROP 0 LAST CDS_SEC 1
J 0
(-3825 5100);
DISPLAY 1.021277 (-3825 5100);
DISPLAY INVISIBLE (-3825 5100);
FORCEPROP 1 LASTPIN (-3875 5025) $PN 1
J 0
(-3865 5005);
DISPLAY 0.489362 (-3865 5005);
PAINT MONO (-3865 5005);
FORCEPROP 1 LASTPIN (-3875 4825) $PN 2
J 0
(-3865 4805);
DISPLAY 0.489362 (-3865 4805);
PAINT MONO (-3865 4805);
FORCEPROP 1 LAST MATERIAL X6S
J 0
(-3825 4850);
DISPLAY 0.489362 (-3825 4850);
PAINT SKYBLUE (-3825 4850);
FORCEPROP 1 LAST TOLERANCE 20%
J 0
(-3825 4900);
DISPLAY 0.489362 (-3825 4900);
PAINT SKYBLUE (-3825 4900);
FORCEPROP 1 LAST VALUE 22UF
J 0
(-3825 5000);
DISPLAY 0.489362 (-3825 5000);
PAINT SKYBLUE (-3825 5000);
FORCEPROP 1 LAST PART_NUMBER TMP_QCH622KMEA01
J 0
(-3825 4750);
DISPLAY 0.489362 (-3825 4750);
PAINT SKYBLUE (-3825 4750);
FORCEPROP 1 LAST VOLTAGE 4V
J 0
(-3825 4950);
DISPLAY 0.489362 (-3825 4950);
PAINT SKYBLUE (-3825 4950);
FORCEPROP 1 LAST PACK_TYPE 0805
J 0
(-3825 4800);
DISPLAY 0.489362 (-3825 4800);
PAINT SKYBLUE (-3825 4800);
FORCEPROP 2 LAST CDS_LIB pure_quanta
J 0
(-3875 4925);
DISPLAY INVISIBLE (-3875 4925);
FORCEPROP 1 LAST PATH I84
J 0
(-3825 5075);
DISPLAY 0.978723 (-3825 5075);
PAINT WHITE (-3825 5075);
DISPLAY INVISIBLE (-3825 5075);
FORCEADD UNIVERSAL_GND..1
(-3875 4600);
FORCEPROP 3 LASTPIN (-3875 4650) SIG_NAME GND\g
J 0
(-3865 4660);
DISPLAY 0.659574 (-3865 4660);
PAINT MONO (-3865 4660);
DISPLAY INVISIBLE (-3865 4660);
FORCEPROP 2 LAST CDS_LIB pure_quanta_power
J 0
(-3875 4600);
PAINT MONO (-3875 4600);
DISPLAY INVISIBLE (-3875 4600);
FORCEPROP 1 LAST PATH I85
J 0
(-3800 4600);
DISPLAY 0.872340 (-3800 4600);
PAINT AQUA (-3800 4600);
DISPLAY INVISIBLE (-3800 4600);
FORCEPROP 1 LAST HDL_POWER GND
J 1
(-3850 4525);
DISPLAY 0.872340 (-3850 4525);
PAINT GREEN (-3850 4525);
DISPLAY INVISIBLE (-3850 4525);
FORCEADD VCC_CORE..1
(-3875 5250);
FORCEPROP 3 LASTPIN (-3875 5200) SIG_NAME PVDDIO_P0\g
J 0
(-3865 5210);
DISPLAY 0.659574 (-3865 5210);
PAINT MONO (-3865 5210);
DISPLAY INVISIBLE (-3865 5210);
FORCEPROP 1 LAST HDL_POWER PVDDIO_P0
J 1
(-3875 5300);
DISPLAY 0.489362 (-3875 5300);
PAINT GREEN (-3875 5300);
FORCEPROP 2 LAST CDS_LIB pure_quanta_power
J 0
(-3875 5250);
DISPLAY INVISIBLE (-3875 5250);
FORCEPROP 1 LAST PATH I86
J 0
(-3825 5275);
DISPLAY 0.872340 (-3825 5275);
PAINT AQUA (-3825 5275);
DISPLAY INVISIBLE (-3825 5275);
FORCEADD VCC_CORE..1
(-6875 3650);
FORCEPROP 3 LASTPIN (-6875 3600) SIG_NAME SW_P12V_STBY_PVDDIO_P0_FLT\g
J 0
(-6865 3610);
DISPLAY 0.659574 (-6865 3610);
PAINT MONO (-6865 3610);
DISPLAY INVISIBLE (-6865 3610);
FORCEPROP 1 LAST HDL_POWER SW_P12V_STBY_PVDDIO_P0_FLT
J 1
(-6875 3700);
DISPLAY 0.489362 (-6875 3700);
PAINT GREEN (-6875 3700);
FORCEPROP 2 LAST CDS_LIB pure_quanta_power
J 0
(-6875 3650);
DISPLAY INVISIBLE (-6875 3650);
FORCEPROP 1 LAST PATH I87
J 0
(-6825 3675);
DISPLAY 0.872340 (-6825 3675);
PAINT AQUA (-6825 3675);
DISPLAY INVISIBLE (-6825 3675);
FORCEADD OFFPAGE..6
(-7300 4875);
FORCEPROP 2 LAST $XR0 182 
J 0
(-7610 4875);
DISPLAY 0.638298 (-7610 4875);
PAINT MONO (-7610 4875);
FORCEPROP 2 LAST PATH I89
J 0
(-7250 4950);
DISPLAY 1.021277 (-7250 4950);
DISPLAY INVISIBLE (-7250 4950);
FORCEPROP 1 LAST COMMENT_BODY TRUE
J 0
(-7200 4800);
DISPLAY 0.872340 (-7200 4800);
PAINT GREEN (-7200 4800);
DISPLAY INVISIBLE (-7200 4800);
FORCEPROP 1 LAST OFFPAGE TRUE
J 0
(-6975 4750);
DISPLAY 0.872340 (-6975 4750);
PAINT GREEN (-6975 4750);
DISPLAY INVISIBLE (-6975 4750);
FORCEPROP 2 LAST CDS_LIB standard
J 0
(-7300 4875);
DISPLAY INVISIBLE (-7300 4875);
FORCEADD Q_INDUCTOR4P_14..1
(-6175 5000);
FORCEPROP 1 LAST LOCATION PL21
J 0
(-6400 5255);
DISPLAY 0.489362 (-6400 5255);
PAINT SKYBLUE (-6400 5255);
FORCEPROP 0 LAST $SEC 1
J 0
(-6100 5325);
DISPLAY 0.680851 (-6100 5325);
PAINT MONO (-6100 5325);
DISPLAY INVISIBLE (-6100 5325);
FORCEPROP 0 LAST CDS_SEC 1
J 0
(-6100 5325);
DISPLAY 1.021277 (-6100 5325);
DISPLAY INVISIBLE (-6100 5325);
FORCEPROP 0 LASTPIN (-6575 5125) $PN 1
J 2
(-6585 5135);
DISPLAY 0.489362 (-6585 5135);
PAINT MONO (-6585 5135);
FORCEPROP 0 LASTPIN (-6575 4875) $PN 2
J 2
(-6585 4885);
DISPLAY 0.489362 (-6585 4885);
PAINT MONO (-6585 4885);
FORCEPROP 0 LASTPIN (-5775 4875) $PN 3
J 0
(-5765 4885);
DISPLAY 0.489362 (-5765 4885);
PAINT MONO (-5765 4885);
FORCEPROP 0 LASTPIN (-5775 5125) $PN 4
J 0
(-5765 5135);
DISPLAY 0.489362 (-5765 5135);
PAINT MONO (-5765 5135);
FORCEPROP 2 LAST PART_TYPE SMLF
J 0
(-6100 5275);
DISPLAY 1.021277 (-6100 5275);
FORCEPROP 1 LAST MATERIAL IND
J 0
(-6375 5175);
DISPLAY 0.489362 (-6375 5175);
PAINT SKYBLUE (-6375 5175);
FORCEPROP 2 LAST VALUE 150NH
J 0
(-6275 5175);
DISPLAY 0.489362 (-6275 5175);
PAINT SKYBLUE (-6275 5175);
FORCEPROP 1 LAST PART_NUMBER CV+15^0TZ04
J 0
(-6125 5175);
DISPLAY 0.489362 (-6125 5175);
PAINT SKYBLUE (-6125 5175);
FORCEPROP 1 LAST NEEDS_NO_SIZE TRUE
J 0
(-6175 5000);
DISPLAY 0.468085 (-6175 5000);
PAINT GREEN (-6175 5000);
DISPLAY INVISIBLE (-6175 5000);
FORCEPROP 2 LAST CDS_LIB pure_quanta
J 0
(-6175 5000);
DISPLAY INVISIBLE (-6175 5000);
FORCEPROP 1 LAST PATH I93
J 0
(-5975 5155);
DISPLAY 0.723404 (-5975 5155);
PAINT GREEN (-5975 5155);
DISPLAY INVISIBLE (-5975 5155);
FORCEADD Q_CAP..1
(-7500 2550);
FORCEPROP 1 LAST LOCATION PC183
J 0
(-7450 2650);
DISPLAY 0.489362 (-7450 2650);
PAINT SKYBLUE (-7450 2650);
FORCEPROP 0 LAST $SEC 1
J 0
(-7450 2700);
DISPLAY 0.680851 (-7450 2700);
PAINT MONO (-7450 2700);
DISPLAY INVISIBLE (-7450 2700);
FORCEPROP 0 LAST CDS_SEC 1
J 2
(-7450 2675);
DISPLAY 1.021277 (-7450 2675);
DISPLAY INVISIBLE (-7450 2675);
FORCEPROP 1 LASTPIN (-7500 2650) $PN 1
J 0
(-7490 2630);
DISPLAY 0.489362 (-7490 2630);
PAINT MONO (-7490 2630);
FORCEPROP 1 LASTPIN (-7500 2450) $PN 2
J 0
(-7490 2430);
DISPLAY 0.489362 (-7490 2430);
PAINT MONO (-7490 2430);
FORCEPROP 1 LAST MATERIAL X7R
J 0
(-7450 2450);
DISPLAY 0.489362 (-7450 2450);
PAINT SKYBLUE (-7450 2450);
FORCEPROP 1 LAST TOLERANCE 10%
J 0
(-7450 2500);
DISPLAY 0.489362 (-7450 2500);
PAINT SKYBLUE (-7450 2500);
FORCEPROP 1 LAST VALUE 0.22UF
J 0
(-7450 2600);
DISPLAY 0.489362 (-7450 2600);
PAINT SKYBLUE (-7450 2600);
FORCEPROP 1 LAST VOLTAGE 16V
J 0
(-7450 2550);
DISPLAY 0.489362 (-7450 2550);
PAINT SKYBLUE (-7450 2550);
FORCEPROP 1 LAST PACK_TYPE 0402
J 0
(-7450 2350);
DISPLAY 0.489362 (-7450 2350);
PAINT SKYBLUE (-7450 2350);
FORCEPROP 1 LAST PART_NUMBER CH4223K1B00
J 0
(-7450 2400);
DISPLAY 0.489362 (-7450 2400);
PAINT SKYBLUE (-7450 2400);
FORCEPROP 2 LAST CDS_LIB pure_quanta
J 2
(-7500 2550);
DISPLAY INVISIBLE (-7500 2550);
FORCEPROP 1 LAST PATH I94
J 0
(-7450 2700);
DISPLAY 0.978723 (-7450 2700);
PAINT WHITE (-7450 2700);
DISPLAY INVISIBLE (-7450 2700);
FORCEADD Q_RES..1
(-6950 1200);
FORCEPROP 1 LAST LOCATION PR112
J 0
(-7000 1225);
DISPLAY 0.489362 (-7000 1225);
PAINT SKYBLUE (-7000 1225);
FORCEPROP 0 LAST $SEC 1
J 0
(-6700 1325);
DISPLAY 0.680851 (-6700 1325);
PAINT MONO (-6700 1325);
DISPLAY INVISIBLE (-6700 1325);
FORCEPROP 0 LAST CDS_SEC 1
J 0
(-6700 1325);
DISPLAY 1.021277 (-6700 1325);
DISPLAY INVISIBLE (-6700 1325);
FORCEPROP 1 LASTPIN (-7050 1200) $PN 1
J 0
(-7038 1212);
DISPLAY 0.787234 (-7038 1212);
PAINT MONO (-7038 1212);
DISPLAY INVISIBLE (-7038 1212);
FORCEPROP 1 LASTPIN (-6850 1200) $PN 2
J 0
(-6888 1212);
DISPLAY 0.787234 (-6888 1212);
PAINT MONO (-6888 1212);
DISPLAY INVISIBLE (-6888 1212);
FORCEPROP 1 LAST WATTAGE 1/16W
J 2
(-6700 1275);
DISPLAY 0.489362 (-6700 1275);
PAINT SKYBLUE (-6700 1275);
FORCEPROP 1 LAST MATERIAL CHIP
J 0
(-6800 1225);
DISPLAY 0.489362 (-6800 1225);
PAINT SKYBLUE (-6800 1225);
FORCEPROP 1 LAST TOLERANCE 5%
J 0
(-7150 1225);
DISPLAY 0.489362 (-7150 1225);
PAINT SKYBLUE (-7150 1225);
FORCEPROP 1 LAST VALUE 0
J 2
(-7175 1225);
DISPLAY 0.489362 (-7175 1225);
PAINT SKYBLUE (-7175 1225);
FORCEPROP 1 LAST PART_NUMBER CS00002JB38
J 0
(-7275 1150);
DISPLAY 0.489362 (-7275 1150);
PAINT SKYBLUE (-7275 1150);
FORCEPROP 1 LAST PACK_TYPE 0402LF
J 0
(-6825 1150);
DISPLAY 0.489362 (-6825 1150);
PAINT SKYBLUE (-6825 1150);
FORCEPROP 2 LAST CDS_LIB pure_quanta
J 0
(-6950 1200);
DISPLAY INVISIBLE (-6950 1200);
FORCEPROP 1 LAST PATH I95
J 0
(-7000 1350);
DISPLAY 0.978723 (-7000 1350);
PAINT WHITE (-7000 1350);
DISPLAY INVISIBLE (-7000 1350);
FORCEADD Q_CAP..1
(-12075 4750);
FORCEPROP 1 LAST LOCATION PC175_9
J 0
(-12025 4850);
DISPLAY 0.489362 (-12025 4850);
PAINT SKYBLUE (-12025 4850);
FORCEPROP 0 LAST $SEC 1
J 0
(-12025 4875);
DISPLAY 0.680851 (-12025 4875);
PAINT MONO (-12025 4875);
DISPLAY INVISIBLE (-12025 4875);
FORCEPROP 0 LAST CDS_SEC 1
J 0
(-11825 4800);
DISPLAY 1.021277 (-11825 4800);
DISPLAY INVISIBLE (-11825 4800);
FORCEPROP 1 LASTPIN (-12075 4850) $PN 1
J 0
(-12065 4830);
DISPLAY 0.489362 (-12065 4830);
PAINT MONO (-12065 4830);
FORCEPROP 1 LASTPIN (-12075 4650) $PN 2
J 0
(-12065 4630);
DISPLAY 0.489362 (-12065 4630);
PAINT MONO (-12065 4630);
FORCEPROP 1 LAST MATERIAL X7R
J 0
(-12025 4650);
DISPLAY 0.489362 (-12025 4650);
PAINT SKYBLUE (-12025 4650);
FORCEPROP 1 LAST TOLERANCE 10%
J 0
(-12025 4700);
DISPLAY 0.489362 (-12025 4700);
PAINT SKYBLUE (-12025 4700);
FORCEPROP 1 LAST VALUE 0.1UF
J 0
(-12025 4800);
DISPLAY 0.489362 (-12025 4800);
PAINT SKYBLUE (-12025 4800);
FORCEPROP 1 LAST PART_NUMBER CH4104K1B00
J 0
(-12025 4600);
DISPLAY 0.489362 (-12025 4600);
PAINT SKYBLUE (-12025 4600);
FORCEPROP 1 LAST VOLTAGE 25V
J 0
(-12025 4750);
DISPLAY 0.489362 (-12025 4750);
PAINT SKYBLUE (-12025 4750);
FORCEPROP 1 LAST PACK_TYPE 0402
J 0
(-12025 4550);
DISPLAY 0.489362 (-12025 4550);
PAINT SKYBLUE (-12025 4550);
FORCEPROP 2 LAST CDS_LIB pure_quanta
J 0
(-12075 4750);
DISPLAY INVISIBLE (-12075 4750);
FORCEPROP 1 LAST PATH I97
J 0
(-12025 4900);
DISPLAY 0.978723 (-12025 4900);
PAINT WHITE (-12025 4900);
DISPLAY INVISIBLE (-12025 4900);
FORCEADD Q_RES..1
(-8150 5475);
FORCEPROP 1 LAST LOCATION PR110
J 0
(-8175 5525);
DISPLAY 0.489362 (-8175 5525);
PAINT SKYBLUE (-8175 5525);
FORCEPROP 0 LAST $SEC 1
J 0
(-7875 5575);
DISPLAY 0.680851 (-7875 5575);
PAINT MONO (-7875 5575);
DISPLAY INVISIBLE (-7875 5575);
FORCEPROP 0 LAST CDS_SEC 1
J 0
(-7875 5575);
DISPLAY 1.021277 (-7875 5575);
DISPLAY INVISIBLE (-7875 5575);
FORCEPROP 1 LASTPIN (-8250 5475) $PN 1
J 0
(-8238 5487);
DISPLAY 0.787234 (-8238 5487);
PAINT MONO (-8238 5487);
DISPLAY INVISIBLE (-8238 5487);
FORCEPROP 1 LASTPIN (-8050 5475) $PN 2
J 0
(-8088 5487);
DISPLAY 0.787234 (-8088 5487);
PAINT MONO (-8088 5487);
DISPLAY INVISIBLE (-8088 5487);
FORCEPROP 1 LAST PACK_TYPE 0402LF
J 0
(-8100 5375);
DISPLAY 0.489362 (-8100 5375);
PAINT SKYBLUE (-8100 5375);
FORCEPROP 1 LAST TOLERANCE 1%
J 0
(-8275 5525);
DISPLAY 0.489362 (-8275 5525);
PAINT SKYBLUE (-8275 5525);
FORCEPROP 1 LAST MATERIAL CHIP
J 0
(-8075 5425);
DISPLAY 0.489362 (-8075 5425);
PAINT SKYBLUE (-8075 5425);
FORCEPROP 1 LAST WATTAGE 1/16W
J 2
(-7950 5500);
DISPLAY 0.489362 (-7950 5500);
PAINT SKYBLUE (-7950 5500);
FORCEPROP 1 LAST PART_NUMBER CS-4702FB19
J 0
(-8475 5425);
DISPLAY 0.489362 (-8475 5425);
PAINT SKYBLUE (-8475 5425);
FORCEPROP 1 LAST VALUE 4.7
J 2
(-8325 5525);
DISPLAY 0.489362 (-8325 5525);
PAINT SKYBLUE (-8325 5525);
FORCEPROP 1 LAST PATH I98
J 0
(-8200 5625);
DISPLAY 0.978723 (-8200 5625);
PAINT WHITE (-8200 5625);
DISPLAY INVISIBLE (-8200 5625);
FORCEPROP 2 LAST CDS_LIB pure_quanta
J 0
(-8150 5475);
DISPLAY INVISIBLE (-8150 5475);
FORCEADD Q_RES..1
(-8375 2675);
FORCEPROP 1 LAST LOCATION PR109
J 0
(-8625 2750);
DISPLAY 0.489362 (-8625 2750);
PAINT SKYBLUE (-8625 2750);
FORCEPROP 0 LAST $SEC 1
J 0
(-8100 2775);
DISPLAY 0.680851 (-8100 2775);
PAINT MONO (-8100 2775);
DISPLAY INVISIBLE (-8100 2775);
FORCEPROP 0 LAST CDS_SEC 1
J 0
(-8100 2775);
DISPLAY 1.021277 (-8100 2775);
DISPLAY INVISIBLE (-8100 2775);
FORCEPROP 1 LASTPIN (-8475 2675) $PN 1
J 0
(-8463 2687);
DISPLAY 0.787234 (-8463 2687);
PAINT MONO (-8463 2687);
DISPLAY INVISIBLE (-8463 2687);
FORCEPROP 1 LASTPIN (-8275 2675) $PN 2
J 0
(-8313 2687);
DISPLAY 0.787234 (-8313 2687);
PAINT MONO (-8313 2687);
DISPLAY INVISIBLE (-8313 2687);
FORCEPROP 1 LAST PACK_TYPE 0402LF
J 0
(-7975 2600);
DISPLAY 0.489362 (-7975 2600);
PAINT SKYBLUE (-7975 2600);
FORCEPROP 1 LAST TOLERANCE 1%
J 0
(-8375 2750);
DISPLAY 0.489362 (-8375 2750);
PAINT SKYBLUE (-8375 2750);
FORCEPROP 1 LAST MATERIAL CHIP
J 0
(-8525 2600);
DISPLAY 0.489362 (-8525 2600);
PAINT SKYBLUE (-8525 2600);
FORCEPROP 1 LAST WATTAGE 1/16W
J 2
(-8100 2750);
DISPLAY 0.489362 (-8100 2750);
PAINT SKYBLUE (-8100 2750);
FORCEPROP 1 LAST VALUE 4.7
J 2
(-8425 2750);
DISPLAY 0.489362 (-8425 2750);
PAINT SKYBLUE (-8425 2750);
FORCEPROP 1 LAST PART_NUMBER CS-4702FB19
J 0
(-8350 2600);
DISPLAY 0.489362 (-8350 2600);
PAINT SKYBLUE (-8350 2600);
FORCEPROP 1 LAST PATH I99
J 0
(-8425 2825);
DISPLAY 0.978723 (-8425 2825);
PAINT WHITE (-8425 2825);
DISPLAY INVISIBLE (-8425 2825);
FORCEPROP 2 LAST CDS_LIB pure_quanta
J 0
(-8375 2675);
DISPLAY INVISIBLE (-8375 2675);
FORCEADD DNS..1
(-8125 4925);
PAINT RED (-8125 4925);
FORCEPROP 2 LAST CDS_LIB mstr_misc
J 0
(-8125 4925);
DISPLAY INVISIBLE (-8125 4925);
FORCEPROP 1 LAST COMMENT_BODY TRUE
R 1
J 0
(-8050 4700);
DISPLAY 0.872340 (-8050 4700);
PAINT GREEN (-8050 4700);
DISPLAY INVISIBLE (-8050 4700);
FORCEADD DNS..1
(-11525 1800);
PAINT RED (-11525 1800);
FORCEPROP 2 LAST CDS_LIB mstr_misc
J 0
(-11525 1800);
PAINT MONO (-11525 1800);
DISPLAY INVISIBLE (-11525 1800);
FORCEPROP 1 LAST COMMENT_BODY TRUE
R 1
J 0
(-11450 1575);
DISPLAY 0.872340 (-11450 1575);
PAINT GREEN (-11450 1575);
DISPLAY INVISIBLE (-11450 1575);
FORCEADD DNS..1
(-8125 2125);
PAINT RED (-8125 2125);
FORCEPROP 2 LAST CDS_LIB mstr_misc
J 0
(-8125 2125);
DISPLAY INVISIBLE (-8125 2125);
FORCEPROP 1 LAST COMMENT_BODY TRUE
R 1
J 0
(-8050 1900);
DISPLAY 0.872340 (-8050 1900);
PAINT GREEN (-8050 1900);
DISPLAY INVISIBLE (-8050 1900);
FORCEADD QUANTA_TITLE_BLOCK_C..1
(-3075 825);
FORCEPROP 0 LAST CDS_CON_LAST_MODIFIED Fri Mar 11 14:53:30 2022
J 0
(-4960 840);
DISPLAY INVISIBLE (-4960 840);
FORCEPROP 1 LAST CUSTOM_TXT_CDS <CON_LAST_MODIFIED>
J 0
(-4960 840);
DISPLAY 0.978723 (-4960 840);
FORCEPROP 2 LAST CUSTOM_TXT_CDS <XR_PAGE_TITLE>
J 0
(-10965 6075);
DISPLAY 0.638298 (-10965 6075);
PAINT PINK (-10965 6075);
DISPLAY INVISIBLE (-10965 6075);
FORCEPROP 1 LAST CUSTOM_TXT_CDS <NAME_2>
J 0
(-6250 875);
FORCEPROP 1 LAST CUSTOM_TXT_CDS <NAME_1>
J 0
(-6250 1000);
FORCEPROP 1 LAST CUSTOM_TXT_CDS <Q_NUMBER>
J 0
(-4478 928);
DISPLAY 1.212766 (-4478 928);
FORCEPROP 1 LAST CUSTOM_TXT_CDS <Q_PROJ>
J 0
(-5457 927);
DISPLAY 1.212766 (-5457 927);
FORCEPROP 1 LAST CUSTOM_TXT_CDS <Q_REV>
J 0
(-3259 928);
DISPLAY 1.212766 (-3259 928);
FORCEPROP 1 LAST CUSTOM_TXT_CDS <CON_PAGE_NUM> OF <CON_TOTAL_PAGES>
J 0
(-3521 843);
DISPLAY 0.978723 (-3521 843);
FORCEPROP 1 LAST Q_DEPT BU9
J 1
(-6838 874);
DISPLAY 1.957447 (-6838 874);
PAINT GREEN (-6838 874);
FORCEPROP 1 LAST Q_TITLE PVDDIO_P0_VR PHASE 3&4
J 0
(-12375 875);
DISPLAY 2.446809 (-12375 875);
PAINT GREEN (-12375 875);
FORCEPROP 2 LAST CDS_LIB pure_quanta
J 0
(-3075 825);
DISPLAY INVISIBLE (-3075 825);
FORCEPROP 1 LAST CDS_LMAN_SYM_OUTLINE -9475,6775,100,-125
J 0
(-3075 825);
DISPLAY 0.468085 (-3075 825);
PAINT GREEN (-3075 825);
DISPLAY INVISIBLE (-3075 825);
FORCEPROP 2 LAST PAGE_BORDER TRUE
J 0
(-10965 6075);
DISPLAY 0.638298 (-10965 6075);
PAINT PINK (-10965 6075);
DISPLAY INVISIBLE (-10965 6075);
FORCEPROP 1 LAST COMMENT_BODY TRUE
J 0
(-3063 812);
DISPLAY 0.978723 (-3063 812);
PAINT GREEN (-3063 812);
DISPLAY INVISIBLE (-3063 812);
FORCEPROP 2 LAST CDS_XR_PAGE_TITLE CR-182 : @T6G_MB_LIB.T6G(SCH_1):PAGE182
J 0
(-10965 6075);
DISPLAY 0.638298 (-10965 6075);
PAINT PINK (-10965 6075);
DISPLAY INVISIBLE (-10965 6075);
FORCEADD DNS..1
(-8125 1600);
PAINT RED (-8125 1600);
FORCEPROP 2 LAST CDS_LIB mstr_misc
J 0
(-8125 1600);
DISPLAY INVISIBLE (-8125 1600);
FORCEPROP 1 LAST COMMENT_BODY TRUE
R 1
J 0
(-8050 1375);
DISPLAY 0.872340 (-8050 1375);
PAINT GREEN (-8050 1375);
DISPLAY INVISIBLE (-8050 1375);
FORCEADD DNS..1
(-8125 4400);
PAINT RED (-8125 4400);
FORCEPROP 2 LAST CDS_LIB mstr_misc
J 0
(-8125 4400);
DISPLAY INVISIBLE (-8125 4400);
FORCEPROP 1 LAST COMMENT_BODY TRUE
R 1
J 0
(-8050 4175);
DISPLAY 0.872340 (-8050 4175);
PAINT GREEN (-8050 4175);
DISPLAY INVISIBLE (-8050 4175);
FORCEADD DNS..1
(-11500 4650);
PAINT RED (-11500 4650);
FORCEPROP 2 LAST CDS_LIB mstr_misc
J 0
(-11500 4650);
PAINT MONO (-11500 4650);
DISPLAY INVISIBLE (-11500 4650);
FORCEPROP 1 LAST COMMENT_BODY TRUE
R 1
J 0
(-11425 4425);
DISPLAY 0.872340 (-11425 4425);
PAINT GREEN (-11425 4425);
DISPLAY INVISIBLE (-11425 4425);
WIRE 16 -1 (-11525 1725)(-11525 1650);
WIRE 16 -1 (-11175 5325)(-11175 5275);
WIRE 16 -1 (-10825 5900)(-10825 5775);
WIRE 16 -1 (-11200 2625)(-11200 2575);
WIRE 16 -1 (-10850 3200)(-10850 3075);
WIRE 16 -1 (-12075 4600)(-12075 4650);
WIRE 16 -1 (-12050 1800)(-12050 1850);
WIRE 16 -1 (-8100 4300)(-8100 4225);
WIRE 16 -1 (-8100 1500)(-8100 1425);
WIRE 16 -1 (-7550 2075)(-7675 2075);
WIRE 16 -1 (-7675 2075)(-7675 2025);
WIRE 16 -1 (-11500 4575)(-11500 4500);
WIRE 16 -1 (-9950 1825)(-11000 1825);
FORCEPROP 2 LAST SIG_NAME PVDDIO_P0_TEMP1
J 0
(-10935 1835);
DISPLAY 0.489362 (-10935 1835);
WIRE 16 -1 (-8850 1825)(-8850 1875);
WIRE 16 -1 (-9100 1825)(-8850 1825);
WIRE 16 -1 (-8850 1825)(-8850 1775);
WIRE 16 -1 (-8850 1875)(-9100 1875);
WIRE 16 -1 (-8850 1775)(-8850 1725);
WIRE 16 -1 (-9100 1775)(-8850 1775);
WIRE 16 -1 (-8850 1725)(-8850 1650);
WIRE 16 -1 (-9100 1725)(-8850 1725);
WIRE 16 -1 (-4675 5125)(-4675 4000);
WIRE 16 -1 (-4675 5125)(-4300 5125);
WIRE 16 -1 (-4675 5125)(-5775 5125);
WIRE 16 -1 (-4675 4000)(-6750 4000);
WIRE 16 -1 (-4300 5125)(-3875 5125);
WIRE 16 -1 (-4300 5125)(-4300 5025);
WIRE 16 -1 (-3875 5200)(-3875 5125);
WIRE 16 -1 (-3875 5025)(-3875 5125);
WIRE 16 -1 (-6575 4875)(-7250 4875);
FORCEPROP 2 LAST SIG_NAME IND_PVDDIO_P0_CPL4
J 0
(-7110 4885);
DISPLAY 0.489362 (-7110 4885);
WIRE 16 -1 (-8100 5025)(-8100 5125);
WIRE 16 -1 (-8100 5125)(-6575 5125);
WIRE 16 -1 (-9100 5125)(-8100 5125);
FORCEPROP 2 LAST SIG_NAME SW_PVDDIO_P0_SW3
J 0
(-8910 5135);
DISPLAY 0.489362 (-8910 5135);
FORCEPROP 2 LASTPROP $XRERR UNIQUE?
J 0
(-9150 5135);
DISPLAY 0.638298 (-9150 5135);
PAINT MONO (-9150 5135);
DISPLAY INVISIBLE (-9150 5135);
WIRE 16 -1 (-7000 6400)(-7000 6325);
WIRE 16 -1 (-7000 6325)(-7000 6200);
WIRE 16 -1 (-7000 6325)(-7425 6325);
WIRE 16 -1 (-7425 6175)(-7425 6325);
WIRE 16 -1 (-7825 6325)(-7425 6325);
WIRE 16 -1 (-7825 6325)(-7825 6175);
WIRE 16 -1 (-8225 6325)(-7825 6325);
WIRE 16 -1 (-8225 6175)(-8225 6325);
WIRE 16 -1 (-8650 6325)(-8225 6325);
WIRE 16 -1 (-8650 6175)(-8650 6325);
WIRE 16 -1 (-8925 6325)(-8650 6325);
WIRE 16 -1 (-8925 6325)(-8925 5775);
WIRE 16 -1 (-8925 5775)(-8925 5725);
WIRE 16 -1 (-9100 5775)(-8925 5775);
WIRE 16 -1 (-8925 5725)(-9100 5725);
WIRE 16 -1 (-9100 4875)(-8375 4875);
FORCEPROP 2 LAST SIG_NAME PVDDIO_P0_VOS3
J 0
(-9010 4900);
DISPLAY 0.489362 (-9010 4900);
FORCEPROP 2 LASTPROP $XRERR UNIQUE?
J 0
(-9250 4900);
DISPLAY 0.638298 (-9250 4900);
PAINT MONO (-9250 4900);
DISPLAY INVISIBLE (-9250 4900);
WIRE 16 -1 (-8375 4875)(-8375 4000);
WIRE 16 -1 (-6950 4000)(-8375 4000);
WIRE 16 -1 (-6875 3375)(-6875 3525);
WIRE 16 -1 (-6875 3600)(-6875 3525);
WIRE 16 -1 (-6875 3525)(-7350 3525);
WIRE 16 -1 (-7350 3375)(-7350 3525);
WIRE 16 -1 (-7750 3525)(-7350 3525);
WIRE 16 -1 (-7750 3525)(-7750 3375);
WIRE 16 -1 (-8150 3525)(-7750 3525);
WIRE 16 -1 (-8150 3375)(-8150 3525);
WIRE 16 -1 (-8625 3525)(-8150 3525);
WIRE 16 -1 (-8625 3400)(-8625 3525);
WIRE 16 -1 (-8925 3525)(-8625 3525);
WIRE 16 -1 (-8925 3525)(-8925 2975);
WIRE 16 -1 (-8925 2975)(-8925 2925);
WIRE 16 -1 (-9100 2975)(-8925 2975);
WIRE 16 -1 (-8925 2925)(-9100 2925);
WIRE 16 -1 (-9100 2425)(-7500 2425);
FORCEPROP 2 LAST SIG_NAME SW_PVDDIO_P0_BOOTR4
J 0
(-8910 2435);
DISPLAY 0.489362 (-8910 2435);
FORCEPROP 2 LASTPROP $XRERR UNIQUE?
J 0
(-9150 2435);
DISPLAY 0.638298 (-9150 2435);
PAINT MONO (-9150 2435);
DISPLAY INVISIBLE (-9150 2435);
WIRE 16 -1 (-7500 2425)(-7500 2450);
WIRE 16 -1 (-8100 2225)(-8100 2325);
WIRE 16 -1 (-8100 2325)(-6825 2325);
WIRE 16 -1 (-9100 2325)(-8100 2325);
FORCEPROP 2 LAST SIG_NAME SW_PVDDIO_P0_SW4
J 0
(-8910 2335);
DISPLAY 0.489362 (-8910 2335);
FORCEPROP 2 LASTPROP $XRERR UNIQUE?
J 0
(-9150 2335);
DISPLAY 0.638298 (-9150 2335);
PAINT MONO (-9150 2335);
DISPLAY INVISIBLE (-9150 2335);
WIRE 16 -1 (-7350 2075)(-6825 2075);
FORCEPROP 2 LAST SIG_NAME IND_PVDDIO_P0_CPL0
J 0
(-7285 2100);
DISPLAY 0.489362 (-7285 2100);
FORCEPROP 2 LASTPROP $XRERR UNIQUE?
J 0
(-7525 2100);
DISPLAY 0.638298 (-7525 2100);
PAINT MONO (-7525 2100);
DISPLAY INVISIBLE (-7525 2100);
WIRE 16 -1 (-8100 2025)(-8100 1700);
FORCEPROP 2 LAST SIG_NAME SW_PVDDIO_P0_SW4_RC
J 0
(-8060 1825);
DISPLAY 0.489362 (-8060 1825);
FORCEPROP 2 LASTPROP $XRERR UNIQUE?
J 0
(-8300 1825);
DISPLAY 0.638298 (-8300 1825);
PAINT MONO (-8300 1825);
DISPLAY INVISIBLE (-8300 1825);
WIRE 16 -1 (-8050 5475)(-7200 5475);
FORCEPROP 2 LAST SIG_NAME SW_PVDDIO_P0_BOOT3_R
J 0
(-7760 5485);
DISPLAY 0.489362 (-7760 5485);
FORCEPROP 2 LASTPROP $XRERR UNIQUE?
J 0
(-8000 5485);
DISPLAY 0.638298 (-8000 5485);
PAINT MONO (-8000 5485);
DISPLAY INVISIBLE (-8000 5485);
WIRE 16 -1 (-7200 5475)(-7200 5450);
WIRE 16 -1 (-7000 5750)(-7000 5825);
WIRE 16 -1 (-7000 6000)(-7000 5825);
WIRE 16 -1 (-7000 5825)(-7425 5825);
WIRE 16 -1 (-7425 5975)(-7425 5825);
WIRE 16 -1 (-7825 5825)(-7425 5825);
WIRE 16 -1 (-7825 5975)(-7825 5825);
WIRE 16 -1 (-7825 5825)(-8225 5825);
WIRE 16 -1 (-8225 5975)(-8225 5825);
WIRE 16 -1 (-8650 5825)(-8225 5825);
WIRE 16 -1 (-8650 5975)(-8650 5825);
WIRE 16 -1 (-9100 5225)(-7200 5225);
FORCEPROP 2 LAST SIG_NAME SW_PVDDIO_P0_BOOTR3
J 0
(-8910 5235);
DISPLAY 0.489362 (-8910 5235);
FORCEPROP 2 LASTPROP $XRERR UNIQUE?
J 0
(-9150 5235);
DISPLAY 0.638298 (-9150 5235);
PAINT MONO (-9150 5235);
DISPLAY INVISIBLE (-9150 5235);
WIRE 16 -1 (-7200 5225)(-7200 5250);
WIRE 16 -1 (-11200 3175)(-11200 2900);
WIRE 16 -1 (-11200 2900)(-10625 2900);
WIRE 16 -1 (-11200 2900)(-11200 2825);
WIRE 16 -1 (-10625 2900)(-10625 2675);
WIRE 16 -1 (-10100 2675)(-10625 2675);
FORCEPROP 0 LAST CDS_PHYS_NET_NAME PVCCFA_EHV_FIVRA_CPU0_VDD2
J 0
(-10510 2715);
PAINT MONO (-10510 2715);
DISPLAY INVISIBLE (-10510 2715);
FORCEPROP 2 LAST SIG_NAME PVDDIO_P0_VCC4
J 0
(-10535 2685);
DISPLAY 0.489362 (-10535 2685);
FORCEPROP 2 LASTPROP $XRERR UNIQUE?
J 0
(-10775 2685);
DISPLAY 0.638298 (-10775 2685);
PAINT MONO (-10775 2685);
DISPLAY INVISIBLE (-10775 2685);
WIRE 16 -1 (-9950 2675)(-10100 2675);
WIRE 16 -1 (-10100 2675)(-10100 2475);
WIRE 16 -1 (-9950 2475)(-10100 2475);
WIRE 16 -1 (-11200 3375)(-11200 3500);
WIRE 16 -1 (-11200 3650)(-11200 3500);
WIRE 16 -1 (-10850 3500)(-11200 3500);
WIRE 16 -1 (-10850 3500)(-10100 3500);
WIRE 16 -1 (-10850 3400)(-10850 3500);
WIRE 16 -1 (-10100 2975)(-10100 3500);
WIRE 16 -1 (-10100 2975)(-9950 2975);
WIRE 16 -1 (-11525 2025)(-9950 2025);
FORCEPROP 2 LAST SIG_NAME PVDDIO_P0_LSET4
J 0
(-10935 2035);
DISPLAY 0.489362 (-10935 2035);
FORCEPROP 2 LASTPROP $XRERR UNIQUE?
J 0
(-11175 2035);
DISPLAY 0.638298 (-11175 2035);
PAINT MONO (-11175 2035);
DISPLAY INVISIBLE (-11175 2035);
WIRE 16 -1 (-11525 2025)(-11525 1925);
WIRE 16 -1 (-10100 2150)(-12050 2150);
WIRE 16 -1 (-10100 2225)(-10100 2150);
FORCEPROP 0 LAST CDS_PHYS_NET_NAME PVCCIN_CPU0_VREF
J 0
(-10100 2175);
PAINT MONO (-10100 2175);
DISPLAY INVISIBLE (-10100 2175);
WIRE 16 -1 (-12050 2150)(-12050 2050);
WIRE 16 -1 (-11000 2225)(-10100 2225);
FORCEPROP 2 LAST SIG_NAME PVDDCR_CPU1_P0_VCCS
J 0
(-10935 2235);
DISPLAY 0.489362 (-10935 2235);
WIRE 16 -1 (-10100 2225)(-9950 2225);
WIRE 16 -1 (-10375 2075)(-9950 2075);
FORCEPROP 2 LAST SIG_NAME NC_PVDDIO_P0_DNC4
J 0
(-10445 2085);
DISPLAY 0.489362 (-10445 2085);
FORCEPROP 2 LASTPROP $XRERR UNIQUE?
J 0
(-10615 2075);
DISPLAY 0.638298 (-10615 2075);
PAINT MONO (-10615 2075);
DISPLAY INVISIBLE (-10615 2075);
WIRE 16 -1 (-9950 1725)(-11000 1725);
FORCEPROP 2 LAST SIG_NAME PVDDIO_P0_PWM4
J 0
(-10935 1735);
DISPLAY 0.489362 (-10935 1735);
WIRE 16 -1 (-9950 2325)(-11000 2325);
FORCEPROP 2 LAST SIG_NAME PVDDIO_P0_IMON4
J 0
(-10935 2335);
DISPLAY 0.489362 (-10935 2335);
WIRE 16 -1 (-9100 2025)(-8600 2025);
FORCEPROP 2 LAST SIG_NAME NC_PVDDIO_P0_GL1_4
J 0
(-8985 2035);
DISPLAY 0.489362 (-8985 2035);
FORCEPROP 2 LASTPROP $XRERR UNIQUE?
J 0
(-8570 2025);
DISPLAY 0.638298 (-8570 2025);
PAINT MONO (-8570 2025);
DISPLAY INVISIBLE (-8570 2025);
WIRE 16 -1 (-9100 1975)(-8600 1975);
FORCEPROP 2 LAST SIG_NAME NC_PVDDIO_P0_GL2_4
J 0
(-8985 1985);
DISPLAY 0.489362 (-8985 1985);
FORCEPROP 2 LASTPROP $XRERR UNIQUE?
J 0
(-8570 1975);
DISPLAY 0.638298 (-8570 1975);
PAINT MONO (-8570 1975);
DISPLAY INVISIBLE (-8570 1975);
WIRE 16 -1 (-9100 2675)(-8475 2675);
FORCEPROP 2 LAST SIG_NAME SW_PVDDIO_P0_BOOT4
J 0
(-8885 2685);
DISPLAY 0.489362 (-8885 2685);
FORCEPROP 2 LASTPROP $XRERR UNIQUE?
J 0
(-9125 2685);
DISPLAY 0.638298 (-9125 2685);
PAINT MONO (-9125 2685);
DISPLAY INVISIBLE (-9125 2685);
WIRE 16 -1 (-9100 2075)(-8375 2075);
FORCEPROP 2 LAST SIG_NAME PVDDIO_P0_VOS4
J 0
(-8985 2100);
DISPLAY 0.489362 (-8985 2100);
FORCEPROP 2 LASTPROP $XRERR UNIQUE?
J 0
(-9225 2100);
DISPLAY 0.638298 (-9225 2100);
PAINT MONO (-9225 2100);
DISPLAY INVISIBLE (-9225 2100);
WIRE 16 -1 (-8375 2075)(-8375 1200);
WIRE 16 -1 (-7050 1200)(-8375 1200);
WIRE 16 -1 (-11175 5600)(-10525 5600);
WIRE 16 -1 (-11175 5875)(-11175 5600);
WIRE 16 -1 (-11175 5600)(-11175 5525);
WIRE 16 -1 (-10525 5475)(-10525 5600);
WIRE 16 -1 (-10100 5475)(-10525 5475);
FORCEPROP 0 LAST CDS_PHYS_NET_NAME PVCCFA_EHV_FIVRA_CPU0_VDD1
J 0
(-10460 5515);
PAINT MONO (-10460 5515);
DISPLAY INVISIBLE (-10460 5515);
FORCEPROP 2 LAST SIG_NAME PVDDIO_P0_VCC3
J 0
(-10485 5485);
DISPLAY 0.489362 (-10485 5485);
FORCEPROP 2 LASTPROP $XRERR UNIQUE?
J 0
(-10725 5485);
DISPLAY 0.638298 (-10725 5485);
PAINT MONO (-10725 5485);
DISPLAY INVISIBLE (-10725 5485);
WIRE 16 -1 (-9950 5475)(-10100 5475);
WIRE 16 -1 (-10100 5475)(-10100 5275);
WIRE 16 -1 (-9950 5275)(-10100 5275);
WIRE 16 -1 (-11175 6075)(-11175 6200);
WIRE 16 -1 (-10825 6200)(-11175 6200);
WIRE 16 -1 (-11175 6350)(-11175 6200);
WIRE 16 -1 (-10825 6100)(-10825 6200);
WIRE 16 -1 (-10500 6200)(-10825 6200);
WIRE 16 -1 (-10500 5775)(-10500 6200);
WIRE 16 -1 (-10500 5775)(-9950 5775);
WIRE 16 -1 (-10375 4875)(-9950 4875);
FORCEPROP 2 LAST SIG_NAME NC_PVDDIO_P0_DNC3
J 0
(-10395 4885);
DISPLAY 0.489362 (-10395 4885);
FORCEPROP 2 LASTPROP $XRERR UNIQUE?
J 0
(-10615 4875);
DISPLAY 0.638298 (-10615 4875);
PAINT MONO (-10615 4875);
DISPLAY INVISIBLE (-10615 4875);
WIRE 16 -1 (-11500 4825)(-9950 4825);
FORCEPROP 0 LAST CDS_PHYS_NET_NAME PVCCFA_EHV_FIVRA_CPU0_LSET1
J 0
(-10910 4865);
PAINT MONO (-10910 4865);
DISPLAY INVISIBLE (-10910 4865);
FORCEPROP 2 LAST SIG_NAME PVDDIO_P0_LSET3
J 0
(-10910 4835);
DISPLAY 0.489362 (-10910 4835);
FORCEPROP 2 LASTPROP $XRERR UNIQUE?
J 0
(-11150 4835);
DISPLAY 0.638298 (-11150 4835);
PAINT MONO (-11150 4835);
DISPLAY INVISIBLE (-11150 4835);
WIRE 16 -1 (-11500 4825)(-11500 4775);
WIRE 16 -1 (-10100 4950)(-12075 4950);
WIRE 16 -1 (-10100 5025)(-10100 4950);
FORCEPROP 0 LAST CDS_PHYS_NET_NAME PVCCIN_CPU0_VREF
J 0
(-10100 4975);
PAINT MONO (-10100 4975);
DISPLAY INVISIBLE (-10100 4975);
WIRE 16 -1 (-12075 4950)(-12075 4850);
WIRE 16 -1 (-10975 5025)(-10100 5025);
FORCEPROP 2 LAST SIG_NAME PVDDCR_CPU1_P0_VCCS
J 0
(-10910 5035);
DISPLAY 0.489362 (-10910 5035);
WIRE 16 -1 (-10100 5025)(-9950 5025);
WIRE 16 -1 (-9950 4525)(-10975 4525);
FORCEPROP 2 LAST SIG_NAME PVDDIO_P0_PWM3
J 0
(-10910 4535);
DISPLAY 0.489362 (-10910 4535);
WIRE 16 -1 (-9950 4625)(-10975 4625);
FORCEPROP 2 LAST SIG_NAME PVDDIO_P0_TEMP1
J 0
(-10910 4635);
DISPLAY 0.489362 (-10910 4635);
WIRE 16 -1 (-9950 5125)(-10975 5125);
FORCEPROP 2 LAST SIG_NAME PVDDIO_P0_IMON3
J 0
(-10910 5135);
DISPLAY 0.489362 (-10910 5135);
WIRE 16 -1 (-8850 4625)(-8850 4675);
WIRE 16 -1 (-9100 4625)(-8850 4625);
WIRE 16 -1 (-8850 4625)(-8850 4575);
WIRE 16 -1 (-8850 4675)(-9100 4675);
WIRE 16 -1 (-8850 4575)(-8850 4525);
WIRE 16 -1 (-9100 4575)(-8850 4575);
WIRE 16 -1 (-8850 4525)(-8850 4450);
WIRE 16 -1 (-9100 4525)(-8850 4525);
WIRE 16 -1 (-8650 4775)(-9100 4775);
FORCEPROP 2 LAST SIG_NAME NC_PVDDIO_P0_GL2_3
J 0
(-9010 4785);
DISPLAY 0.489362 (-9010 4785);
FORCEPROP 2 LASTPROP $XRERR UNIQUE?
J 0
(-8620 4775);
DISPLAY 0.638298 (-8620 4775);
PAINT MONO (-8620 4775);
DISPLAY INVISIBLE (-8620 4775);
WIRE 16 -1 (-8650 4825)(-9100 4825);
FORCEPROP 2 LAST SIG_NAME NC_PVDDIO_P0_GL1_3
J 0
(-9010 4835);
DISPLAY 0.489362 (-9010 4835);
FORCEPROP 2 LASTPROP $XRERR UNIQUE?
J 0
(-8620 4825);
DISPLAY 0.638298 (-8620 4825);
PAINT MONO (-8620 4825);
DISPLAY INVISIBLE (-8620 4825);
WIRE 16 -1 (-9100 5475)(-8250 5475);
FORCEPROP 2 LAST SIG_NAME SW_PVDDIO_P0_BOOT3
J 0
(-8910 5510);
DISPLAY 0.489362 (-8910 5510);
FORCEPROP 2 LASTPROP $XRERR UNIQUE?
J 0
(-9150 5510);
DISPLAY 0.638298 (-9150 5510);
PAINT MONO (-9150 5510);
DISPLAY INVISIBLE (-9150 5510);
WIRE 16 -1 (-8625 3200)(-8625 3025);
WIRE 16 -1 (-8625 3025)(-8150 3025);
WIRE 16 -1 (-8150 3175)(-8150 3025);
WIRE 16 -1 (-7750 3025)(-8150 3025);
WIRE 16 -1 (-7750 3175)(-7750 3025);
WIRE 16 -1 (-7750 3025)(-7350 3025);
WIRE 16 -1 (-6875 3025)(-7350 3025);
WIRE 16 -1 (-7350 3175)(-7350 3025);
WIRE 16 -1 (-6875 3175)(-6875 3025);
WIRE 16 -1 (-6875 2950)(-6875 3025);
WIRE 16 -1 (-8275 2675)(-7500 2675);
FORCEPROP 2 LAST SIG_NAME SW_PVDDIO_P0_BOOT4_R
J 0
(-7985 2685);
DISPLAY 0.489362 (-7985 2685);
FORCEPROP 2 LASTPROP $XRERR UNIQUE?
J 0
(-8225 2685);
DISPLAY 0.638298 (-8225 2685);
PAINT MONO (-8225 2685);
DISPLAY INVISIBLE (-8225 2685);
WIRE 16 -1 (-7500 2675)(-7500 2650);
WIRE 16 -1 (-4975 1200)(-4975 2325);
WIRE 16 -1 (-4975 1200)(-6850 1200);
WIRE 16 -1 (-4350 2325)(-4975 2325);
WIRE 16 -1 (-4975 2325)(-6025 2325);
WIRE 16 -1 (-4350 2325)(-3925 2325);
WIRE 16 -1 (-4350 2225)(-4350 2325);
WIRE 16 -1 (-3925 2400)(-3925 2325);
WIRE 16 -1 (-3925 2225)(-3925 2325);
WIRE 16 -1 (-6025 2075)(-5475 2075);
FORCEPROP 2 LAST SIG_NAME IND_PVDDIO_P0_CPL4
J 0
(-5985 2085);
DISPLAY 0.489362 (-5985 2085);
WIRE 16 -1 (-8100 4825)(-8100 4500);
FORCEPROP 2 LAST SIG_NAME SW_PVDDIO_P0_SW3_RC
J 0
(-8060 4635);
DISPLAY 0.489362 (-8060 4635);
FORCEPROP 2 LASTPROP $XRERR UNIQUE?
J 0
(-8300 4635);
DISPLAY 0.638298 (-8300 4635);
PAINT MONO (-8300 4635);
DISPLAY INVISIBLE (-8300 4635);
WIRE 16 -1 (-5775 4875)(-5225 4875);
FORCEPROP 2 LAST SIG_NAME IND_PVDDIO_P0_CPL3
J 0
(-5660 4885);
DISPLAY 0.489362 (-5660 4885);
WIRE 16 -1 (-3925 1900)(-4350 1900);
WIRE 16 -1 (-3925 1825)(-3925 1900);
WIRE 16 -1 (-3925 2025)(-3925 1900);
WIRE 16 -1 (-4350 1900)(-4350 2025);
WIRE 16 -1 (-3875 4700)(-4300 4700);
WIRE 16 -1 (-3875 4650)(-3875 4700);
WIRE 16 -1 (-3875 4825)(-3875 4700);
WIRE 16 -1 (-4300 4700)(-4300 4825);
DOT 1 (-8850 1725);
DOT 1 (-8850 1825);
DOT 1 (-10100 5475);
DOT 1 (-7425 5825);
DOT 1 (-4975 2325);
DOT 1 (-10100 2225);
DOT 1 (-11200 2900);
DOT 1 (-10850 3500);
DOT 1 (-8850 1775);
DOT 1 (-10100 2675);
DOT 1 (-8925 2975);
DOT 1 (-8625 3525);
DOT 1 (-11175 5600);
DOT 1 (-10825 6200);
DOT 1 (-10100 5025);
DOT 1 (-8850 4525);
DOT 1 (-8850 4575);
DOT 1 (-8850 4625);
DOT 1 (-8650 6325);
DOT 1 (-8225 6325);
DOT 1 (-7750 3025);
DOT 1 (-7350 3025);
DOT 1 (-7750 3525);
DOT 1 (-7350 3525);
DOT 1 (-7825 5825);
DOT 1 (-7000 5825);
DOT 1 (-7825 6325);
DOT 1 (-7425 6325);
DOT 1 (-7000 6325);
DOT 1 (-4300 5125);
DOT 1 (-4675 5125);
DOT 1 (-3875 4700);
DOT 1 (-3875 5125);
DOT 1 (-8925 5775);
DOT 1 (-8150 3025);
DOT 1 (-6875 3025);
DOT 1 (-6875 3525);
DOT 1 (-4350 2325);
DOT 1 (-3925 1900);
DOT 1 (-3925 2325);
DOT 1 (-8100 5125);
DOT 1 (-11175 6200);
DOT 1 (-11200 3500);
DOT 1 (-8225 5825);
DOT 1 (-8150 3525);
DOT 1 (-8100 2325);
FORCENOTE
HCME656510Q-221QL
(-7575 2000) 0;
DISPLAY LEFT (-7575 2000);
DISPLAY 0.638298 (-7575 2000);
PAINT WHITE (-7575 2000);
FORCENOTE
2ND=CV+22Y0EZ01
(-7575 1800) 0;
DISPLAY LEFT (-7575 1800);
DISPLAY 0.638298 (-7575 1800);
PAINT WHITE (-7575 1800);
FORCENOTE
ISAT:30A@100C
(-7575 1950) 0;
DISPLAY LEFT (-7575 1950);
DISPLAY 0.638298 (-7575 1950);
PAINT WHITE (-7575 1950);
FORCENOTE
DCR=0.17M OHM
(-7575 1850) 0;
DISPLAY LEFT (-7575 1850);
DISPLAY 0.638298 (-7575 1850);
PAINT WHITE (-7575 1850);
FORCENOTE
DCR=2-3,0.27M OHM
(-5750 5225) 0;
DISPLAY LEFT (-5750 5225);
DISPLAY 0.638298 (-5750 5225);
PAINT WHITE (-5750 5225);
FORCENOTE
2ND=CV+15^0TZ01
(-5750 5175) 0;
DISPLAY LEFT (-5750 5175);
DISPLAY 0.638298 (-5750 5175);
PAINT WHITE (-5750 5175);
FORCENOTE
2ND=CV+15^0TZ01
(-6000 2400) 0;
DISPLAY LEFT (-6000 2400);
DISPLAY 0.638298 (-6000 2400);
PAINT WHITE (-6000 2400);
FORCENOTE
DCR=2-3,0.27M OHM
(-6000 2450) 0;
DISPLAY LEFT (-6000 2450);
DISPLAY 0.638298 (-6000 2450);
PAINT WHITE (-6000 2450);
FORCENOTE
DCR=1-4,0.105M OHM
(-6000 2500) 0;
DISPLAY LEFT (-6000 2500);
DISPLAY 0.638298 (-6000 2500);
PAINT WHITE (-6000 2500);
FORCENOTE
PGL6303.151HLT
(-5750 5425) 0;
DISPLAY LEFT (-5750 5425);
DISPLAY 0.638298 (-5750 5425);
PAINT WHITE (-5750 5425);
FORCENOTE
11.0*7.5*12.5
(-5750 5325) 0;
DISPLAY LEFT (-5750 5325);
DISPLAY 0.638298 (-5750 5325);
PAINT WHITE (-5750 5325);
FORCENOTE
DCR=1-4,0.105M OHM
(-5750 5275) 0;
DISPLAY LEFT (-5750 5275);
DISPLAY 0.638298 (-5750 5275);
PAINT WHITE (-5750 5275);
FORCENOTE
ISAT:70A@100C
(-5750 5375) 0;
DISPLAY LEFT (-5750 5375);
DISPLAY 0.638298 (-5750 5375);
PAINT WHITE (-5750 5375);
FORCENOTE
PGL6303.151HLT
(-6000 2650) 0;
DISPLAY LEFT (-6000 2650);
DISPLAY 0.638298 (-6000 2650);
PAINT WHITE (-6000 2650);
FORCENOTE
11.0*7.5*12.5
(-6000 2550) 0;
DISPLAY LEFT (-6000 2550);
DISPLAY 0.638298 (-6000 2550);
PAINT WHITE (-6000 2550);
FORCENOTE
ISAT:70A@100C
(-6000 2600) 0;
DISPLAY LEFT (-6000 2600);
DISPLAY 0.638298 (-6000 2600);
PAINT WHITE (-6000 2600);
FORCENOTE
PVDDIO_P0_PHASE3
(-9800 6250) 0;
DISPLAY LEFT (-9800 6250);
DISPLAY 1.021277 (-9800 6250);
PAINT WHITE (-9800 6250);
FORCENOTE
PVDDIO_P0_PHASE4
(-9800 3400) 0;
DISPLAY LEFT (-9800 3400);
DISPLAY 1.021277 (-9800 3400);
PAINT WHITE (-9800 3400);
FORCENOTE
6.5*6.5*10.0
(-7575 1900) 0;
DISPLAY LEFT (-7575 1900);
DISPLAY 0.638298 (-7575 1900);
PAINT WHITE (-7575 1900);
QUIT
